G04 ================== begin FILE IDENTIFICATION RECORD ==================*
G04 Layout Name:  F:/<user>/2022/FB/R4006-TIMING/brd/gerber-3/R4006-B0001-02_R01.brd*
G04 Film Name:    R4006-B0001-02_R01_BAS*
G04 File Format:  Gerber RS274X*
G04 File Origin:  Cadence Allegro 17.2-S079*
G04 Origin Date:  Fri Feb 25 18:14:44 2022*
G04 *
G04 Layer:  PACKAGE GEOMETRY/ASSEMBLY_BOTTOM*
G04 Layer:  BOARD GEOMETRY/OUTLINE*
G04 Layer:  REF DES/ASSEMBLY_BOTTOM*
G04 Layer:  MANUFACTURING/CELESTICA_LEGEND*
G04 *
G04 Offset:    (0.00 0.00)*
G04 Mirror:    No*
G04 Mode:      Positive*
G04 Rotation:  0*
G04 FullContactRelief:  No*
G04 UndefLineWidth:     6.00*
G04 ================== end FILE IDENTIFICATION RECORD ====================*
%FSLAX55Y55*MOIN*%
%IR0*IPPOS*OFA0.00000B0.00000*MIA0B0*SFA1.00000B1.00000*%
%ADD10C,.01*%
%ADD11C,.005*%
%ADD12C,.006*%
%ADD13C,.007*%
%ADD14C,.008*%
G75*
%LPD*%
G75*
G36*
G01X51400Y302700D02*
G03I-1500J0D01*
G37*
G36*
G01X190957Y353777D02*
G02I-1500J0D01*
G37*
G36*
G01X248470Y213852D02*
G03I-1500J0D01*
G37*
G36*
G01X273330Y223622D02*
G02I-590J0D01*
G37*
G36*
G01X296500Y225000D02*
G03I-1500J0D01*
G37*
G36*
G01X312000Y222000D02*
G03I-1500J0D01*
G37*
G36*
G01X575000Y266600D02*
G02I-750J0D01*
G37*
G36*
G01X574500Y295100D02*
G02I-750J0D01*
G37*
G36*
G01X539376Y369755D02*
Y367755D01*
X523824D01*
Y369755D01*
X539376D01*
G37*
G54D10*
G01X136000Y-65500D02*
Y-158000D01*
X506000D01*
Y-65500D01*
X136000D01*
G01X316000D02*
Y-158000D01*
G54D11*
G01X329433Y-125500D02*
Y-133000D01*
X333167D01*
G01X340480D02*
Y-128000D01*
G01Y-128875D02*
X340107Y-128375D01*
X339547Y-128125D01*
X338893Y-128000D01*
X338240Y-128250D01*
X337680Y-128750D01*
X337307Y-129500D01*
X337120Y-130500D01*
X337307Y-131500D01*
X337680Y-132250D01*
X338240Y-132750D01*
X338893Y-133000D01*
X339547Y-132875D01*
X340107Y-132500D01*
X340480Y-132000D01*
G01X344340Y-135250D02*
X344900Y-135500D01*
X345647Y-135250D01*
X346113Y-134750D01*
X346487Y-134125D01*
X347047Y-132125D01*
X348260Y-128000D01*
G01X345273D02*
X347047Y-132125D01*
G01X352400Y-129625D02*
X355387D01*
X355107Y-128750D01*
X354640Y-128250D01*
X353987Y-128000D01*
X353333Y-128125D01*
X352773Y-128500D01*
X352400Y-129375D01*
X352213Y-130125D01*
Y-130875D01*
X352400Y-131625D01*
X352867Y-132375D01*
X353427Y-132875D01*
X354080Y-133000D01*
X354733Y-132750D01*
X355387Y-132000D01*
G01X359993Y-133000D02*
Y-128000D01*
G01Y-129000D02*
X360460Y-128500D01*
X360927Y-128125D01*
X361580Y-128000D01*
X362047Y-128125D01*
X362607Y-128500D01*
G01X368800Y-133250D02*
X368613Y-133125D01*
Y-132875D01*
X368800Y-132750D01*
X368987Y-132875D01*
Y-133125D01*
X368800Y-133250D01*
G01Y-129875D02*
X368613Y-129750D01*
Y-129500D01*
X368800Y-129375D01*
X368987Y-129500D01*
Y-129750D01*
X368800Y-129875D01*
G01X336747Y-120500D02*
Y-113000D01*
X338613D01*
X339360Y-113375D01*
X339920Y-113875D01*
X340387Y-114625D01*
X340760Y-115500D01*
X340853Y-116750D01*
X340760Y-118000D01*
X340387Y-118875D01*
X339920Y-119625D01*
X339360Y-120125D01*
X338613Y-120500D01*
X336747D01*
G01X347980D02*
Y-115500D01*
G01Y-116375D02*
X347607Y-115875D01*
X347047Y-115625D01*
X346393Y-115500D01*
X345740Y-115750D01*
X345180Y-116250D01*
X344807Y-117000D01*
X344620Y-118000D01*
X344807Y-119000D01*
X345180Y-119750D01*
X345740Y-120250D01*
X346393Y-120500D01*
X347047Y-120375D01*
X347607Y-120000D01*
X347980Y-119500D01*
G01X353800Y-113000D02*
Y-120500D01*
G01X352493Y-115500D02*
X355107D01*
G01X359900Y-117125D02*
X362887D01*
X362607Y-116250D01*
X362140Y-115750D01*
X361487Y-115500D01*
X360833Y-115625D01*
X360273Y-116000D01*
X359900Y-116875D01*
X359713Y-117625D01*
Y-118375D01*
X359900Y-119125D01*
X360367Y-119875D01*
X360927Y-120375D01*
X361580Y-120500D01*
X362233Y-120250D01*
X362887Y-119500D01*
G01X368800Y-120750D02*
X368613Y-120625D01*
Y-120375D01*
X368800Y-120250D01*
X368987Y-120375D01*
Y-120625D01*
X368800Y-120750D01*
G01Y-117375D02*
X368613Y-117250D01*
Y-117000D01*
X368800Y-116875D01*
X368987Y-117000D01*
Y-117250D01*
X368800Y-117375D01*
G01X382027Y-114250D02*
X382587Y-113500D01*
X383240Y-113125D01*
X383987Y-113000D01*
X384920Y-113250D01*
X385573Y-113875D01*
X385760Y-114625D01*
X385667Y-115375D01*
X385293Y-116000D01*
X383427Y-117250D01*
X382587Y-118125D01*
X382027Y-119375D01*
X381840Y-120500D01*
X385760D01*
G01X391300Y-113000D02*
X390553Y-113250D01*
X389993Y-113875D01*
X389620Y-114625D01*
X389340Y-115625D01*
X389247Y-116750D01*
X389340Y-117875D01*
X389620Y-118875D01*
X389993Y-119625D01*
X390553Y-120250D01*
X391300Y-120500D01*
X392047Y-120250D01*
X392607Y-119625D01*
X392980Y-118875D01*
X393260Y-117875D01*
X393353Y-116750D01*
X393260Y-115625D01*
X392980Y-114625D01*
X392607Y-113875D01*
X392047Y-113250D01*
X391300Y-113000D01*
G01X397027Y-114250D02*
X397587Y-113500D01*
X398240Y-113125D01*
X398987Y-113000D01*
X399920Y-113250D01*
X400573Y-113875D01*
X400760Y-114625D01*
X400667Y-115375D01*
X400293Y-116000D01*
X398427Y-117250D01*
X397587Y-118125D01*
X397027Y-119375D01*
X396840Y-120500D01*
X400760D01*
G01X404527Y-114250D02*
X405087Y-113500D01*
X405740Y-113125D01*
X406487Y-113000D01*
X407420Y-113250D01*
X408073Y-113875D01*
X408260Y-114625D01*
X408167Y-115375D01*
X407793Y-116000D01*
X405927Y-117250D01*
X405087Y-118125D01*
X404527Y-119375D01*
X404340Y-120500D01*
X408260D01*
G01X412587Y-118000D02*
X415013D01*
G01X421300Y-113000D02*
X420553Y-113250D01*
X419993Y-113875D01*
X419620Y-114625D01*
X419340Y-115625D01*
X419247Y-116750D01*
X419340Y-117875D01*
X419620Y-118875D01*
X419993Y-119625D01*
X420553Y-120250D01*
X421300Y-120500D01*
X422047Y-120250D01*
X422607Y-119625D01*
X422980Y-118875D01*
X423260Y-117875D01*
X423353Y-116750D01*
X423260Y-115625D01*
X422980Y-114625D01*
X422607Y-113875D01*
X422047Y-113250D01*
X421300Y-113000D01*
G01X427027Y-114250D02*
X427587Y-113500D01*
X428240Y-113125D01*
X428987Y-113000D01*
X429920Y-113250D01*
X430573Y-113875D01*
X430760Y-114625D01*
X430667Y-115375D01*
X430293Y-116000D01*
X428427Y-117250D01*
X427587Y-118125D01*
X427027Y-119375D01*
X426840Y-120500D01*
X430760D01*
G01X435087Y-118000D02*
X437513D01*
G01X442027Y-114250D02*
X442587Y-113500D01*
X443240Y-113125D01*
X443987Y-113000D01*
X444920Y-113250D01*
X445573Y-113875D01*
X445760Y-114625D01*
X445667Y-115375D01*
X445293Y-116000D01*
X443427Y-117250D01*
X442587Y-118125D01*
X442027Y-119375D01*
X441840Y-120500D01*
X445760D01*
G01X449247Y-119375D02*
X449807Y-120000D01*
X450460Y-120375D01*
X451300Y-120500D01*
X452140Y-120250D01*
X452793Y-119750D01*
X453260Y-118875D01*
X453353Y-117875D01*
X453167Y-116875D01*
X452700Y-116250D01*
X452047Y-115750D01*
X451393Y-115625D01*
X450740Y-115750D01*
X449900Y-116250D01*
X450180Y-113000D01*
X452700D01*
G01X336933Y-108000D02*
Y-100500D01*
X339267D01*
X340013Y-100875D01*
X340480Y-101375D01*
X340667Y-102375D01*
X340480Y-103375D01*
X339920Y-104000D01*
X339267Y-104375D01*
X336933D01*
G01X339267D02*
X340667Y-108000D01*
G01X344900Y-104625D02*
X347887D01*
X347607Y-103750D01*
X347140Y-103250D01*
X346487Y-103000D01*
X345833Y-103125D01*
X345273Y-103500D01*
X344900Y-104375D01*
X344713Y-105125D01*
Y-105875D01*
X344900Y-106625D01*
X345367Y-107375D01*
X345927Y-107875D01*
X346580Y-108000D01*
X347233Y-107750D01*
X347887Y-107000D01*
G01X352120Y-103000D02*
X353800Y-108000D01*
X355480Y-103000D01*
G01X368800Y-108250D02*
X368613Y-108125D01*
Y-107875D01*
X368800Y-107750D01*
X368987Y-107875D01*
Y-108125D01*
X368800Y-108250D01*
G01Y-104875D02*
X368613Y-104750D01*
Y-104500D01*
X368800Y-104375D01*
X368987Y-104500D01*
Y-104750D01*
X368800Y-104875D01*
G01X383800Y-100500D02*
X383053Y-100750D01*
X382493Y-101375D01*
X382120Y-102125D01*
X381840Y-103125D01*
X381747Y-104250D01*
X381840Y-105375D01*
X382120Y-106375D01*
X382493Y-107125D01*
X383053Y-107750D01*
X383800Y-108000D01*
X384547Y-107750D01*
X385107Y-107125D01*
X385480Y-106375D01*
X385760Y-105375D01*
X385853Y-104250D01*
X385760Y-103125D01*
X385480Y-102125D01*
X385107Y-101375D01*
X384547Y-100750D01*
X383800Y-100500D01*
G01X391300Y-108000D02*
Y-100500D01*
X390180Y-102000D01*
G01Y-108000D02*
X392420D01*
G01X336933Y-95500D02*
Y-88000D01*
X339173D01*
X339920Y-88375D01*
X340480Y-89250D01*
X340667Y-90250D01*
X340480Y-91250D01*
X340013Y-92000D01*
X339173Y-92375D01*
X336933D01*
G01X344620Y-95750D02*
X347980Y-88000D01*
G01X351653Y-95500D02*
Y-88000D01*
X355947Y-95500D01*
Y-88000D01*
G01X368800Y-95750D02*
X368613Y-95625D01*
Y-95375D01*
X368800Y-95250D01*
X368987Y-95375D01*
Y-95625D01*
X368800Y-95750D01*
G01Y-92375D02*
X368613Y-92250D01*
Y-92000D01*
X368800Y-91875D01*
X368987Y-92000D01*
Y-92250D01*
X368800Y-92375D01*
G01X381933Y-95500D02*
Y-88000D01*
X384267D01*
X385013Y-88375D01*
X385480Y-88875D01*
X385667Y-89875D01*
X385480Y-90875D01*
X384920Y-91500D01*
X384267Y-91875D01*
X381933D01*
G01X384267D02*
X385667Y-95500D01*
G01X392420D02*
Y-88000D01*
X388967Y-93375D01*
X393633D01*
G01X398800Y-88000D02*
X398053Y-88250D01*
X397493Y-88875D01*
X397120Y-89625D01*
X396840Y-90625D01*
X396747Y-91750D01*
X396840Y-92875D01*
X397120Y-93875D01*
X397493Y-94625D01*
X398053Y-95250D01*
X398800Y-95500D01*
X399547Y-95250D01*
X400107Y-94625D01*
X400480Y-93875D01*
X400760Y-92875D01*
X400853Y-91750D01*
X400760Y-90625D01*
X400480Y-89625D01*
X400107Y-88875D01*
X399547Y-88250D01*
X398800Y-88000D01*
G01X406300D02*
X405553Y-88250D01*
X404993Y-88875D01*
X404620Y-89625D01*
X404340Y-90625D01*
X404247Y-91750D01*
X404340Y-92875D01*
X404620Y-93875D01*
X404993Y-94625D01*
X405553Y-95250D01*
X406300Y-95500D01*
X407047Y-95250D01*
X407607Y-94625D01*
X407980Y-93875D01*
X408260Y-92875D01*
X408353Y-91750D01*
X408260Y-90625D01*
X407980Y-89625D01*
X407607Y-88875D01*
X407047Y-88250D01*
X406300Y-88000D01*
G01X412027Y-92375D02*
X412680Y-91500D01*
X413240Y-91000D01*
X413987Y-90750D01*
X414640Y-91000D01*
X415107Y-91500D01*
X415480Y-92250D01*
X415573Y-93125D01*
X415480Y-93875D01*
X415107Y-94625D01*
X414547Y-95250D01*
X413893Y-95500D01*
X413147Y-95250D01*
X412493Y-94500D01*
X412120Y-93375D01*
X412027Y-92125D01*
X412213Y-90500D01*
X412493Y-89625D01*
X412960Y-88750D01*
X413613Y-88125D01*
X414267Y-88000D01*
X414920Y-88250D01*
X415387Y-88875D01*
G01X420087Y-93000D02*
X422513D01*
G01X429547Y-91500D02*
X429920Y-91125D01*
X430200Y-90500D01*
X430387Y-89625D01*
X430200Y-88875D01*
X429827Y-88375D01*
X429173Y-88000D01*
X426653D01*
Y-95500D01*
X429733D01*
X430387Y-95000D01*
X430760Y-94250D01*
X430947Y-93375D01*
X430760Y-92500D01*
X430200Y-91750D01*
X429547Y-91500D01*
X426653D01*
G01X436300Y-88000D02*
X435553Y-88250D01*
X434993Y-88875D01*
X434620Y-89625D01*
X434340Y-90625D01*
X434247Y-91750D01*
X434340Y-92875D01*
X434620Y-93875D01*
X434993Y-94625D01*
X435553Y-95250D01*
X436300Y-95500D01*
X437047Y-95250D01*
X437607Y-94625D01*
X437980Y-93875D01*
X438260Y-92875D01*
X438353Y-91750D01*
X438260Y-90625D01*
X437980Y-89625D01*
X437607Y-88875D01*
X437047Y-88250D01*
X436300Y-88000D01*
G01X443800D02*
X443053Y-88250D01*
X442493Y-88875D01*
X442120Y-89625D01*
X441840Y-90625D01*
X441747Y-91750D01*
X441840Y-92875D01*
X442120Y-93875D01*
X442493Y-94625D01*
X443053Y-95250D01*
X443800Y-95500D01*
X444547Y-95250D01*
X445107Y-94625D01*
X445480Y-93875D01*
X445760Y-92875D01*
X445853Y-91750D01*
X445760Y-90625D01*
X445480Y-89625D01*
X445107Y-88875D01*
X444547Y-88250D01*
X443800Y-88000D01*
G01X451300D02*
X450553Y-88250D01*
X449993Y-88875D01*
X449620Y-89625D01*
X449340Y-90625D01*
X449247Y-91750D01*
X449340Y-92875D01*
X449620Y-93875D01*
X449993Y-94625D01*
X450553Y-95250D01*
X451300Y-95500D01*
X452047Y-95250D01*
X452607Y-94625D01*
X452980Y-93875D01*
X453260Y-92875D01*
X453353Y-91750D01*
X453260Y-90625D01*
X452980Y-89625D01*
X452607Y-88875D01*
X452047Y-88250D01*
X451300Y-88000D01*
G01X458800Y-95500D02*
Y-88000D01*
X457680Y-89500D01*
G01Y-95500D02*
X459920D01*
G01X465087Y-93000D02*
X467513D01*
G01X473800Y-88000D02*
X473053Y-88250D01*
X472493Y-88875D01*
X472120Y-89625D01*
X471840Y-90625D01*
X471747Y-91750D01*
X471840Y-92875D01*
X472120Y-93875D01*
X472493Y-94625D01*
X473053Y-95250D01*
X473800Y-95500D01*
X474547Y-95250D01*
X475107Y-94625D01*
X475480Y-93875D01*
X475760Y-92875D01*
X475853Y-91750D01*
X475760Y-90625D01*
X475480Y-89625D01*
X475107Y-88875D01*
X474547Y-88250D01*
X473800Y-88000D01*
G01X479527Y-89250D02*
X480087Y-88500D01*
X480740Y-88125D01*
X481487Y-88000D01*
X482420Y-88250D01*
X483073Y-88875D01*
X483260Y-89625D01*
X483167Y-90375D01*
X482793Y-91000D01*
X480927Y-92250D01*
X480087Y-93125D01*
X479527Y-94375D01*
X479340Y-95500D01*
X483260D01*
G01X381106Y-132929D02*
X383439Y-125429D01*
X385772Y-132929D01*
G01X384932Y-130304D02*
X381946D01*
G01X388979Y-131929D02*
X389726Y-132554D01*
X390566Y-132929D01*
X391312D01*
X392059Y-132554D01*
X392619Y-131929D01*
X392899Y-131054D01*
X392712Y-130179D01*
X392246Y-129429D01*
X391406Y-128929D01*
X390286Y-128679D01*
X389632Y-128179D01*
X389352Y-127304D01*
X389539Y-126429D01*
X390006Y-125804D01*
X390659Y-125429D01*
X391312D01*
X391966Y-125679D01*
X392526Y-126304D01*
G01X396479Y-131929D02*
X397226Y-132554D01*
X398066Y-132929D01*
X398812D01*
X399559Y-132554D01*
X400119Y-131929D01*
X400399Y-131054D01*
X400212Y-130179D01*
X399746Y-129429D01*
X398906Y-128929D01*
X397786Y-128679D01*
X397132Y-128179D01*
X396852Y-127304D01*
X397039Y-126429D01*
X397506Y-125804D01*
X398159Y-125429D01*
X398812D01*
X399466Y-125679D01*
X400026Y-126304D01*
G01X407806Y-132929D02*
X404072D01*
Y-125429D01*
X407806D01*
G01X406312Y-129054D02*
X404072D01*
G01X411012Y-132929D02*
Y-125429D01*
X413439Y-131679D01*
X415866Y-125429D01*
Y-132929D01*
G01X421686Y-128929D02*
X422059Y-128554D01*
X422339Y-127929D01*
X422526Y-127054D01*
X422339Y-126304D01*
X421966Y-125804D01*
X421312Y-125429D01*
X418792D01*
Y-132929D01*
X421872D01*
X422526Y-132429D01*
X422899Y-131679D01*
X423086Y-130804D01*
X422899Y-129929D01*
X422339Y-129179D01*
X421686Y-128929D01*
X418792D01*
G01X426572Y-125429D02*
Y-132929D01*
X430306D01*
G01X435939D02*
Y-129554D01*
X434072Y-125429D01*
G01X437806D02*
X435939Y-129554D01*
G01X451686Y-128929D02*
X452059Y-128554D01*
X452339Y-127929D01*
X452526Y-127054D01*
X452339Y-126304D01*
X451966Y-125804D01*
X451312Y-125429D01*
X448792D01*
Y-132929D01*
X451872D01*
X452526Y-132429D01*
X452899Y-131679D01*
X453086Y-130804D01*
X452899Y-129929D01*
X452339Y-129179D01*
X451686Y-128929D01*
X448792D01*
G01X458439Y-132929D02*
X457692Y-132804D01*
X457039Y-132304D01*
X456479Y-131554D01*
X456106Y-130679D01*
X455919Y-129679D01*
Y-128679D01*
X456106Y-127679D01*
X456479Y-126804D01*
X457039Y-126054D01*
X457692Y-125554D01*
X458439Y-125429D01*
X459186Y-125554D01*
X459839Y-126054D01*
X460399Y-126804D01*
X460772Y-127679D01*
X460959Y-128679D01*
Y-129679D01*
X460772Y-130679D01*
X460399Y-131554D01*
X459839Y-132304D01*
X459186Y-132804D01*
X458439Y-132929D01*
G01X465939Y-125429D02*
Y-132929D01*
G01X463792Y-125429D02*
X468086D01*
G54D12*
G01X658071Y284646D02*
G03X660039Y286614I0J1968D01*
G01Y433661D01*
G03X656102Y437598I-3937J0D01*
G01X3937D01*
G03X0Y433661I0J-3937D01*
G01Y21654D01*
G03X3937Y17717I3937J0D01*
G01X55118D01*
G03X59055Y21654I0J3937D01*
G01Y46260D01*
G02X62992Y50197I3937J0D01*
G01X127362D01*
G02X131299Y46260I0J-3937D01*
G01Y21654D01*
G03X135236Y17717I3937J0D01*
G01X158858D01*
G03X162795Y21654I0J3937D01*
G01Y43012D01*
G02X177165I7185J0D01*
G01Y1969D01*
X179134Y0D01*
X219291D01*
X221260Y1969D01*
Y29331D01*
G02X228740I3740J0D01*
G01Y1969D01*
X230709Y0D01*
X310236D01*
X312205Y1969D01*
Y46260D01*
G02X316142Y50197I3937J0D01*
G01X656102D01*
G03X660039Y54134I0J3937D01*
G01Y237500D01*
G03X658071Y239469I-1969J1D01*
G01X657211D01*
G02X655243Y241437I0J1968D01*
G01Y282677D01*
G02X657211Y284646I1968J0D01*
G01X658071D01*
G01X41328Y36811D02*
G02I-11800J0D01*
G01X20000Y296300D02*
Y298700D01*
G01X24000Y296300D02*
X20000D01*
G01X24000Y298700D02*
Y296300D01*
G01X20000Y298700D02*
X24000D01*
G01Y303700D02*
Y301300D01*
G01X20000D02*
Y303700D01*
G01X24000Y301300D02*
X20000D01*
G01Y291300D02*
Y293700D01*
G01X24000Y291300D02*
X20000D01*
G01X24000Y293700D02*
Y291300D01*
G01X20000Y293700D02*
X24000D01*
G01Y288700D02*
Y286300D01*
G01X20000Y288700D02*
X24000D01*
G01X20000Y286300D02*
Y288700D01*
G01X24000Y286300D02*
X20000D01*
G01Y306300D02*
Y308700D01*
G01X24000Y306300D02*
X20000D01*
G01X24000Y308700D02*
Y306300D01*
G01X20000Y308700D02*
X24000D01*
G01X20000Y303700D02*
X24000D01*
G01X41328Y373031D02*
G02I-11800J0D01*
G01X34700Y283000D02*
X32300D01*
G01X34700Y287000D02*
Y283000D01*
G01X32300D02*
Y287000D01*
G01X27800Y283000D02*
Y287000D01*
G01X30200Y283000D02*
X27800D01*
G01X30200Y287000D02*
Y283000D01*
G01X32300Y287000D02*
X34700D01*
G01X27800D02*
X30200D01*
G01X40000Y293000D02*
X52000D01*
G01X40000Y305000D02*
Y293000D01*
G01X52000Y305000D02*
X40000D01*
G01X56500Y69600D02*
X58900D01*
G01X56500Y65600D02*
Y69600D01*
G01X58900Y65600D02*
X56500D01*
G01X58900Y69600D02*
Y65600D01*
G01X54200D02*
X51800D01*
G01X54200Y69600D02*
Y65600D01*
G01X51800Y69600D02*
X54200D01*
G01X51800Y65600D02*
Y69600D01*
G01X52300Y92500D02*
X54700D01*
G01X52300Y88500D02*
Y92500D01*
G01X54700Y88500D02*
X52300D01*
G01X54700Y92500D02*
Y88500D01*
G01X51800Y144500D02*
Y148500D01*
G01X54200Y144500D02*
X51800D01*
G01X54200Y148500D02*
Y144500D01*
G01X51800Y148500D02*
X54200D01*
G01X51800Y209000D02*
X54200D01*
G01X51800Y205000D02*
Y209000D01*
G01X54200Y205000D02*
X51800D01*
G01X54200Y209000D02*
Y205000D01*
G01X51800Y262500D02*
X54200D01*
G01X51800Y258500D02*
Y262500D01*
G01X54200Y258500D02*
X51800D01*
G01X54200Y262500D02*
Y258500D01*
G01X52000Y293000D02*
Y305000D01*
G01X63600Y60300D02*
Y62700D01*
G01X67600Y60300D02*
X63600D01*
G01X67600Y62700D02*
Y60300D01*
G01X63600Y62700D02*
X67600D01*
G01X78700Y75200D02*
X81100D01*
G01X78700Y71200D02*
Y75200D01*
G01X81100Y71200D02*
X78700D01*
G01X70900Y85800D02*
X73300D01*
G01X70900Y81800D02*
Y85800D01*
G01X73300Y81800D02*
X70900D01*
G01X73300Y85800D02*
Y81800D01*
G01X75500Y91200D02*
X73100D01*
G01X75500Y95200D02*
Y91200D01*
G01X73100D02*
Y95200D01*
G01X80000Y91200D02*
X77600D01*
G01D02*
Y95200D01*
G01X68600Y91200D02*
Y95200D01*
G01X71000Y91200D02*
X68600D01*
G01X71000Y95200D02*
Y91200D01*
G01X73100Y95200D02*
X75500D01*
G01X77600D02*
X80000D01*
G01X68600D02*
X71000D01*
G01X67600Y153200D02*
Y155600D01*
G01X71600Y153200D02*
X67600D01*
G01X71600Y155600D02*
Y153200D01*
G01X67600Y155600D02*
X71600D01*
G01X67500Y148300D02*
Y150700D01*
G01X71500Y148300D02*
X67500D01*
G01X71500Y150700D02*
Y148300D01*
G01X67500Y150700D02*
X71500D01*
G01X67700Y158700D02*
Y161100D01*
G01X71700Y158700D02*
X67700D01*
G01X71700Y161100D02*
Y158700D01*
G01X67700Y161100D02*
X71700D01*
G01X74800Y244300D02*
X77200D01*
G01X74800Y240300D02*
Y244300D01*
G01X77200Y240300D02*
X74800D01*
G01X77200Y244300D02*
Y240300D01*
G01X79300Y244300D02*
X81700D01*
G01X79300Y240300D02*
Y244300D01*
G01X81700Y240300D02*
X79300D01*
G01X72700D02*
X70300D01*
G01X72700Y244300D02*
Y240300D01*
G01X70300Y244300D02*
X72700D01*
G01X70300Y240300D02*
Y244300D01*
G01X64800Y301500D02*
Y305500D01*
G01X67200Y301500D02*
X64800D01*
G01X67200Y305500D02*
Y301500D01*
G01X74000Y292700D02*
Y290300D01*
G01X70000Y292700D02*
X74000D01*
G01X70000Y290300D02*
Y292700D01*
G01X74000Y290300D02*
X70000D01*
G01X64800Y305500D02*
X67200D01*
G01X70500Y318800D02*
Y321200D01*
G01X74500Y318800D02*
X70500D01*
G01X74500Y321200D02*
Y318800D01*
G01Y316700D02*
Y314300D01*
G01X70500Y316700D02*
X74500D01*
G01X70500Y314300D02*
Y316700D01*
G01X74500Y314300D02*
X70500D01*
G01Y323300D02*
Y325700D01*
G01X74500Y323300D02*
X70500D01*
G01X74500Y325700D02*
Y323300D01*
G01X70500Y325700D02*
X74500D01*
G01X70500Y321200D02*
X74500D01*
G01X68800Y342500D02*
X71200D01*
G01X68800Y338500D02*
Y342500D01*
G01X71200Y338500D02*
X68800D01*
G01X71200Y342500D02*
Y338500D01*
G01X84800Y69800D02*
Y72200D01*
G01X88800Y69800D02*
X84800D01*
G01X88800Y72200D02*
Y69800D01*
G01X84800Y72200D02*
X88800D01*
G01X85000Y67700D02*
Y65300D01*
G01X81000Y67700D02*
X85000D01*
G01X81000Y65300D02*
Y67700D01*
G01X85000Y65300D02*
X81000D01*
G01X81100Y75200D02*
Y71200D01*
G01X87200Y79200D02*
X84800D01*
G01X87200Y83200D02*
Y79200D01*
G01X84800Y83200D02*
X87200D01*
G01X84800Y79200D02*
Y83200D01*
G01X80000Y95200D02*
Y91200D01*
G01X86600D02*
Y95200D01*
G01X89000Y91200D02*
X86600D01*
G01X89000Y95200D02*
Y91200D01*
G01X82100D02*
Y95200D01*
G01X84500Y91200D02*
X82100D01*
G01X84500Y95200D02*
Y91200D01*
G01X86600Y95200D02*
X89000D01*
G01X82100D02*
X84500D01*
G01X84900Y165100D02*
Y162700D01*
G01X80900D02*
Y165100D01*
G01X84900Y162700D02*
X80900D01*
G01X84900Y160600D02*
Y158200D01*
G01X80900Y160600D02*
X84900D01*
G01X80900Y158200D02*
Y160600D01*
G01X84900Y158200D02*
X80900D01*
G01X84500Y151200D02*
Y148800D01*
G01X80500Y151200D02*
X84500D01*
G01X80500Y148800D02*
Y151200D01*
G01X84500Y148800D02*
X80500D01*
G01X84900Y156100D02*
Y153700D01*
G01X80900Y156100D02*
X84900D01*
G01X80900Y153700D02*
Y156100D01*
G01X84900Y153700D02*
X80900D01*
G01X84900Y169600D02*
Y167200D01*
G01X80900Y169600D02*
X84900D01*
G01X80900Y167200D02*
Y169600D01*
G01X84900Y167200D02*
X80900D01*
G01Y165100D02*
X84900D01*
G01X81700Y244300D02*
Y240300D01*
G01X90800D02*
X88400D01*
G01X90800Y244300D02*
Y240300D01*
G01X88400Y244300D02*
X90800D01*
G01X88400Y240300D02*
Y244300D01*
G01X86200Y240300D02*
X83800D01*
G01X86200Y244300D02*
Y240300D01*
G01X83800Y244300D02*
X86200D01*
G01X83800Y240300D02*
Y244300D01*
G01X89600Y283000D02*
X92000D01*
G01X89600Y279000D02*
Y283000D01*
G01X92000Y279000D02*
X89600D01*
G01X92000Y283000D02*
Y279000D01*
G01X87000D02*
X84600D01*
G01X87000Y283000D02*
Y279000D01*
G01X84600Y283000D02*
X87000D01*
G01X84600Y279000D02*
Y283000D01*
G01X87000Y344300D02*
Y346700D01*
G01X91000Y344300D02*
X87000D01*
G01X91000Y346700D02*
Y344300D01*
G01X87000Y346700D02*
X91000D01*
G01X87000Y348800D02*
Y351200D01*
G01X91000Y348800D02*
X87000D01*
G01X91000Y351200D02*
Y348800D01*
G01X87000Y351200D02*
X91000D01*
G01X87000Y339800D02*
Y342200D01*
G01X91000Y339800D02*
X87000D01*
G01X91000Y342200D02*
Y339800D01*
G01X87000Y342200D02*
X91000D01*
G01X96200Y356500D02*
X93800D01*
G01X96200Y360500D02*
Y356500D01*
G01X93800Y360500D02*
X96200D01*
G01X93800Y356500D02*
Y360500D01*
G01X89400Y355400D02*
X87000D01*
G01X89400Y359400D02*
Y355400D01*
G01X87000D02*
Y359400D01*
G01D02*
X89400D01*
G01X107900Y73000D02*
Y70600D01*
G01X103900Y73000D02*
X107900D01*
G01X103900Y70600D02*
Y73000D01*
G01X107900Y70600D02*
X103900D01*
G01X102300Y313500D02*
X104700D01*
G01X102300Y309500D02*
Y313500D01*
G01X104700Y309500D02*
X102300D01*
G01X104700Y313500D02*
Y309500D01*
G01X107200Y345300D02*
X110800D01*
G01X107200Y351700D02*
Y345300D01*
G01X110800Y351700D02*
X107200D01*
G01X110800Y345300D02*
Y351700D01*
G01X114200Y356500D02*
X111800D01*
G01X114200Y360500D02*
Y356500D01*
G01X111800Y360500D02*
X114200D01*
G01X111800Y356500D02*
Y360500D01*
G01X104300Y369000D02*
Y373000D01*
G01X106700Y369000D02*
X104300D01*
G01X106700Y373000D02*
Y369000D01*
G01X98300Y360500D02*
X100700D01*
G01X98300Y356500D02*
Y360500D01*
G01X100700Y356500D02*
X98300D01*
G01X100700Y360500D02*
Y356500D01*
G01X102800Y360500D02*
X105200D01*
G01X102800Y356500D02*
Y360500D01*
G01X105200Y356500D02*
X102800D01*
G01X105200Y360500D02*
Y356500D01*
G01X109700D02*
X107300D01*
G01X109700Y360500D02*
Y356500D01*
G01X107300Y360500D02*
X109700D01*
G01X107300Y356500D02*
Y360500D01*
G01X104300Y373000D02*
X106700D01*
G01X131000Y74100D02*
Y76500D01*
G01X135000Y74100D02*
X131000D01*
G01X121470Y72060D02*
Y69660D01*
G01X117470Y72060D02*
X121470D01*
G01X117470Y69660D02*
Y72060D01*
G01X121470Y69660D02*
X117470D01*
G01X117480Y64670D02*
Y67070D01*
G01X121480Y64670D02*
X117480D01*
G01X121480Y67070D02*
Y64670D01*
G01X117480Y67070D02*
X121480D01*
G01X130950Y67000D02*
X134950D01*
G01X130950Y64600D02*
Y67000D01*
G01X134950Y64600D02*
X130950D01*
G01X130970Y72000D02*
X134970D01*
G01X130970Y69600D02*
Y72000D01*
G01X134970Y69600D02*
X130970D01*
G01X131000Y76500D02*
X135000D01*
G01X155567Y106043D02*
G02I-12000J0D01*
G01X126800Y313500D02*
X129200D01*
G01X126800Y309500D02*
Y313500D01*
G01X129200Y309500D02*
X126800D01*
G01X129200Y313500D02*
Y309500D01*
G01X115500Y346300D02*
Y348700D01*
G01X119500Y346300D02*
X115500D01*
G01X119500Y348700D02*
Y346300D01*
G01X115500Y348700D02*
X119500D01*
G01X130200Y354300D02*
X133800D01*
G01X130200Y360700D02*
Y354300D01*
G01X127700Y356500D02*
X125300D01*
G01X127700Y360500D02*
Y356500D01*
G01X125300Y360500D02*
X127700D01*
G01X125300Y356500D02*
Y360500D01*
G01X118700Y356500D02*
X116300D01*
G01X118700Y360500D02*
Y356500D01*
G01X116300Y360500D02*
X118700D01*
G01X116300Y356500D02*
Y360500D01*
G01X123200Y356500D02*
X120800D01*
G01X123200Y360500D02*
Y356500D01*
G01X120800Y360500D02*
X123200D01*
G01X120800Y356500D02*
Y360500D01*
G01X133800Y360700D02*
X130200D01*
G01X145964Y-110118D02*
G03I-634J0D01*
G01X149695D02*
G03I-1038J0D01*
G01X135000Y76500D02*
Y74100D01*
G01X134950Y67000D02*
Y64600D01*
G01X134970Y72000D02*
Y69600D01*
G01X158067Y268043D02*
G02I-12000J0D01*
G01X148000Y301200D02*
X152000D01*
G01X148000Y298800D02*
Y301200D01*
G01X152000Y298800D02*
X148000D01*
G01X134000Y326800D02*
Y329200D01*
G01X138000Y326800D02*
X134000D01*
G01X138000Y329200D02*
Y326800D01*
G01X134000Y329200D02*
X138000D01*
G01X134000Y322300D02*
Y324700D01*
G01X138000Y322300D02*
X134000D01*
G01X138000Y324700D02*
Y322300D01*
G01X134000Y324700D02*
X138000D01*
G01X133500Y348800D02*
Y351200D01*
G01X137500Y348800D02*
X133500D01*
G01X137500Y351200D02*
Y348800D01*
G01X133500Y351200D02*
X137500D01*
G01X133800Y354300D02*
Y360700D01*
G01X136300Y360000D02*
X138700D01*
G01X136300Y356000D02*
Y360000D01*
G01X138700Y356000D02*
X136300D01*
G01X138700Y360000D02*
Y356000D01*
G01X143600Y388900D02*
Y391300D01*
G01X147600Y388900D02*
X143600D01*
G01X147600Y391300D02*
Y388900D01*
G01X142600Y383900D02*
Y386300D01*
G01X146600Y383900D02*
X142600D01*
G01X146600Y386300D02*
Y383900D01*
G01X142600Y386300D02*
X146600D01*
G01X143600Y402400D02*
Y404800D01*
G01X147600Y402400D02*
X143600D01*
G01X147600Y404800D02*
Y402400D01*
G01X143600Y404800D02*
X147600D01*
G01X143600Y391300D02*
X147600D01*
G01Y395800D02*
Y393400D01*
G01X143600Y395800D02*
X147600D01*
G01X143600Y393400D02*
Y395800D01*
G01X147600Y393400D02*
X143600D01*
G01X147600Y400300D02*
Y397900D01*
G01X143600Y400300D02*
X147600D01*
G01X143600Y397900D02*
Y400300D01*
G01X147600Y397900D02*
X143600D01*
G01X141300Y410800D02*
Y407200D01*
G01X147700D02*
Y410800D01*
G01X141300Y407200D02*
X147700D01*
G01Y410800D02*
X141300D01*
G01X147600Y415400D02*
Y413000D01*
G01X143600Y415400D02*
X147600D01*
G01X143600Y413000D02*
Y415400D01*
G01X147600Y413000D02*
X143600D01*
G01X168013Y-137456D02*
G03I-634J0D01*
G01X155900Y-133655D02*
G03I-632J0D01*
G01X161735Y-128639D02*
G03I-1458J0D01*
G01X158530Y-131428D02*
G03I-1041J0D01*
G01X158461Y-119126D02*
G03I-1283J0D01*
G01X162690Y-117490D02*
G03I-1584J0D01*
G01X169809Y-121292D02*
G03I-2180J0D01*
G01X165531Y-125255D02*
G03I-1869J0D01*
G01X167813Y-115513D02*
G03I-1971J0D01*
G01X154775Y-120500D02*
G03I-892J0D01*
G01X162681Y-102774D02*
G03I-1584J0D01*
G01X158451Y-101149D02*
G03I-1283J0D01*
G01X159258Y-110118D02*
G03I-1868J0D01*
G01X169812Y-98951D02*
G03I-2180J0D01*
G01X167802Y-104739D02*
G03I-1971J0D01*
G01X165183Y-110118D02*
G03I-2180J0D01*
G01X171881D02*
G03I-2642J0D01*
G01X152135Y-98681D02*
G03I-632J0D01*
G01X154064Y-110118D02*
G03I-1460J0D01*
G01X154764Y-99775D02*
G03I-892J0D01*
G01X158530Y-88809D02*
G03I-1041J0D01*
G01X161742Y-91601D02*
G03I-1458J0D01*
G01X165531Y-94981D02*
G03I-1869J0D01*
G01X152000Y301200D02*
Y298800D01*
G01X161800Y354500D02*
X164200D01*
G01X161800Y350500D02*
Y354500D01*
G01X164200Y350500D02*
X161800D01*
G01X164200Y354500D02*
Y350500D01*
G01X158100Y378800D02*
Y376400D01*
G01X154100Y378800D02*
X158100D01*
G01X154100Y376400D02*
Y378800D01*
G01X158100Y376400D02*
X154100D01*
G01X162500Y387300D02*
Y389700D01*
G01X166500Y387300D02*
X162500D01*
G01X166500Y389700D02*
Y387300D01*
G01X162500Y389700D02*
X166500D01*
G01X163650Y402150D02*
Y404050D01*
G01X162550Y402150D02*
X163650D01*
G01X162550Y404050D02*
Y402150D01*
G01X163650Y404050D02*
X162550D01*
G01X171080Y-131739D02*
G03I-1282J0D01*
G01X169322Y-135033D02*
G03I-892J0D01*
G01X180669Y-131528D02*
G03I-1870J0D01*
G01X180255Y-136311D02*
G03I-1456J0D01*
G01X179841Y-140261D02*
G03I-1042J0D01*
G01X179433Y-143587D02*
G03I-634J0D01*
G01X181439Y-119680D02*
G03I-2640J0D01*
G01X175373Y-123081D02*
G03I-1968J0D01*
G01X173018Y-127816D02*
G03I-1584J0D01*
G01X174681Y-116876D02*
G03I-2640J0D01*
G01X180979Y-125917D02*
G03I-2180J0D01*
G01X186177Y-123075D02*
G03I-1971J0D01*
G01X188199Y-116876D02*
G03I-2640J0D01*
G01X175452Y-97124D02*
G03I-1968J0D01*
G01X186225Y-97178D02*
G03I-1971J0D01*
G01X181439Y-100556D02*
G03I-2640J0D01*
G01X174681Y-103361D02*
G03I-2640J0D01*
G01X188199D02*
G03I-2640J0D01*
G01X179841Y-79975D02*
G03I-1042J0D01*
G01X171217Y-88444D02*
G03I-1282J0D01*
G01X173123Y-92378D02*
G03I-1584J0D01*
G01X180255Y-83924D02*
G03I-1456J0D01*
G01X180669Y-88708D02*
G03I-1870J0D01*
G01X180979Y-94320D02*
G03I-2180J0D01*
G01X179433Y-76648D02*
G03I-634J0D01*
G01X177200Y1981D02*
Y36281D01*
G01X179200Y-19D02*
X177200Y1981D01*
G01X219250Y-19D02*
X179200D01*
G01X178200Y336650D02*
X193600D01*
G01X178200Y355950D02*
Y336650D01*
G01X174100Y338000D02*
X178200D01*
G01X174100Y339600D02*
Y338000D01*
G01Y353000D02*
X178200D01*
G01X174100Y354600D02*
Y353000D01*
G01X178200Y354600D02*
X174100D01*
G01Y348000D02*
X178200D01*
G01X174100Y349600D02*
Y348000D01*
G01X178200Y349600D02*
X174100D01*
G01Y343000D02*
X178200D01*
G01X174100Y344600D02*
Y343000D01*
G01X178200Y344600D02*
X174100D01*
G01X178200Y339600D02*
X174100D01*
G01X193600Y355950D02*
X178200D01*
G01X172500Y389800D02*
Y392200D01*
G01X176500Y389800D02*
X172500D01*
G01X176500Y392200D02*
Y389800D01*
G01X172500Y392200D02*
X176500D01*
G01X181200Y402500D02*
X178800D01*
G01X181200Y406500D02*
Y402500D01*
G01X178800Y406500D02*
X181200D01*
G01X178800Y402500D02*
Y406500D01*
G01X188000Y410500D02*
X180000D01*
G01Y415500D02*
X188000D01*
G01X180000Y410500D02*
Y415500D01*
G01X191096Y-134658D02*
G03I-892J0D01*
G01X192135Y-136781D02*
G03I-631J0D01*
G01X198775Y-128635D02*
G03I-1458J0D01*
G01X195808Y-125255D02*
G03I-1869J0D01*
G01X200547Y-113952D02*
G03X203345Y-117196I7247J3422D01*
G01X192148Y-121285D02*
G03I-2180J0D01*
G01X187928Y-127802D02*
G03I-1584J0D01*
G01X189667Y-131511D02*
G03I-1283J0D01*
G01X200699Y-105836D02*
G03X200547Y-113953I8974J-4228D01*
G01X208284Y-101612D02*
G03X200698Y-105835I-219J-8531D01*
G01X192148Y-98951D02*
G03I-2180J0D01*
G01X191108Y-82727D02*
G03I-634J0D01*
G01X190184Y-85250D02*
G03I-893J0D01*
G01X195808Y-94981D02*
G03I-1869J0D01*
G01X187839Y-92457D02*
G03I-1584J0D01*
G01X189190Y-88538D02*
G03I-1283J0D01*
G01X187660Y60320D02*
X185260D01*
G01X187660Y64320D02*
Y60320D01*
G01X185260Y64320D02*
X187660D01*
G01X185260Y60320D02*
Y64320D01*
G01X189700Y294000D02*
X187300D01*
G01X189700Y298000D02*
Y294000D01*
G01X187300Y298000D02*
X189700D01*
G01X187300Y294000D02*
Y298000D01*
G01X193600Y336650D02*
Y355950D01*
G01X197700Y338000D02*
X193600D01*
G01X197700Y339600D02*
Y338000D01*
G01X193600Y339600D02*
X197700D01*
G01Y343000D02*
X193600D01*
G01X197700Y344600D02*
Y343000D01*
G01X193600Y344600D02*
X197700D01*
G01Y348000D02*
X193600D01*
G01X197700Y349600D02*
Y348000D01*
G01X193600Y349600D02*
X197700D01*
G01Y353000D02*
X193600D01*
G01X197700Y354600D02*
Y353000D01*
G01X193600Y354600D02*
X197700D01*
G01X188000Y415500D02*
Y410500D01*
G01X214259Y-115661D02*
G03X213314Y-114453I-714J415D01*
G01X202049Y-108260D02*
G03X205722Y-116181I7039J-1548D01*
G01X218075Y-112869D02*
G03X219083Y-115752I4343J-99D01*
G01X208854Y-116658D02*
G03X213313Y-114452I-2485J10632D01*
G01X208470Y-118462D02*
G03X214261Y-115663I-1122J9711D01*
G01X203346Y-117195D02*
G03X208470Y-118461I4545J7394D01*
G01X205721Y-116179D02*
G03X208853Y-116659I2561J6250D01*
G01X215903Y-114020D02*
G03X219079Y-118061I6190J1597D01*
G01X215904Y-114020D02*
Y-111835D01*
G01X227413Y-112869D02*
X218074D01*
G01X214175Y-103951D02*
G03X208283Y-101613I-6403J-7542D01*
G01X213150Y-105147D02*
G03X214175Y-103951I410J686D01*
G01X213152Y-105146D02*
G03X208030Y-103430I-5122J-6786D01*
G01X208029Y-103429D02*
G03X202049Y-108259I-48J-6058D01*
G01X225189Y-111399D02*
G03X218071I-3559J159D01*
G01X218070Y-111418D02*
Y-111399D01*
G01X225188Y-111418D02*
X218070D01*
G01X227412Y-111835D02*
G03X215906I-5753J223D01*
G01X216700Y61500D02*
X214300D01*
G01X216700Y65500D02*
Y61500D01*
G01X214300Y65500D02*
X216700D01*
G01X214300Y61500D02*
Y65500D01*
G01X221200Y61500D02*
X218800D01*
G01Y65500D02*
X221200D01*
G01X218800Y61500D02*
Y65500D01*
G01X216100Y297200D02*
X218500D01*
G01X216100Y293200D02*
Y297200D01*
G01X218500Y293200D02*
X216100D01*
G01X218500Y297200D02*
Y293200D01*
G01X211600Y297200D02*
X214000D01*
G01X211600Y293200D02*
Y297200D01*
G01X214000Y293200D02*
X211600D01*
G01X214000Y297200D02*
Y293200D01*
G01X207100Y297200D02*
X209500D01*
G01X207100Y293200D02*
Y297200D01*
G01X209500Y293200D02*
X207100D01*
G01X209500Y297200D02*
Y293200D01*
G01X214500Y337200D02*
Y334800D01*
G01X210500Y337200D02*
X214500D01*
G01X210500Y334800D02*
Y337200D01*
G01X214500Y334800D02*
X210500D01*
G01X209300Y345000D02*
X211700D01*
G01X209300Y341000D02*
Y345000D01*
G01X211700Y341000D02*
X209300D01*
G01X211700Y345000D02*
Y341000D01*
G01X214500Y356200D02*
Y353800D01*
G01X210500D02*
Y356200D01*
G01X214500Y353800D02*
X210500D01*
G01X214500Y351200D02*
Y348800D01*
G01X210500Y351200D02*
X214500D01*
G01X210500Y348800D02*
Y351200D01*
G01X214500Y348800D02*
X210500D01*
G01Y356200D02*
X214500D01*
G01X230059Y-117625D02*
Y-102034D01*
G01X230060Y-117626D02*
G03X232080I1010J239D01*
G01X226590Y-116472D02*
G03X225311Y-115210I-817J451D01*
G01X234673Y-114020D02*
G03X237849Y-118061I6190J1597D01*
G01X232081Y-102041D02*
Y-117625D01*
G01X219083Y-115753D02*
G03X225311Y-115211I2844J3371D01*
G01X219079Y-118060D02*
G03X226591Y-116473I2662J5972D01*
G01X227413Y-111835D02*
Y-112869D01*
G01X232080Y-102041D02*
G03X230060Y-102034I-1011J-236D01*
G01X225188Y-111399D02*
Y-111418D01*
G01X234675Y-114020D02*
Y-111835D01*
G01X246181D02*
G03X234675I-5753J223D01*
G01X221250Y1981D02*
X219250Y-19D01*
G01X221250Y29331D02*
Y1981D01*
G01X228750D02*
Y29331D01*
G01X230750Y-19D02*
X228750Y1981D01*
G01X310200Y-19D02*
X230750D01*
G01X225000Y33081D02*
G03X221250Y29331I0J-3750D01*
G01X228750D02*
G03X225000Y33081I-3750J0D01*
G01X235510Y58490D02*
X233110D01*
G01X235510Y62490D02*
Y58490D01*
G01X233110D02*
Y62490D01*
G01X221200Y65500D02*
Y61500D01*
G01X233110Y62490D02*
X235510D01*
G01X224200Y61800D02*
X227800D01*
G01X224200Y68200D02*
Y61800D01*
G01X227800Y68200D02*
X224200D01*
G01X227800Y61800D02*
Y68200D01*
G01X252849Y-116771D02*
G03X254892Y-115895I-74J2994D01*
G01X236844Y-112869D02*
G03X237852Y-115752I4343J-99D01*
G01X237848Y-118060D02*
G03X245360Y-116473I2662J5972D01*
G01X245358Y-116472D02*
G03X244079Y-115210I-817J451D01*
G01X237852Y-115753D02*
G03X244080Y-115211I2844J3371D01*
G01X249566Y-115529D02*
G03X252307Y-116760I2985J2980D01*
G01Y-116761D02*
G03X252849Y-116772I366J4691D01*
G01X250282Y-118087D02*
G03X254318Y-118340I2605J9244D01*
G01X247897Y-116444D02*
G03X250283Y-118086I3752J2898D01*
G01X249568Y-115529D02*
G03X247898Y-116443I-748J-616D01*
G01X255608Y-108618D02*
G03X253612Y-107689I-3116J-4086D01*
G01X246181Y-111835D02*
Y-112869D01*
G01D02*
X236844D01*
G01X255002Y-114328D02*
G03X252723Y-112986I-3540J-3405D01*
G01X249955Y-112030D02*
G03X252723Y-112985I8208J19302D01*
G01X243957Y-111399D02*
Y-111418D01*
G01X243958Y-111399D02*
G03X236840I-3559J159D01*
G01X236841Y-111418D02*
Y-111399D01*
G01X243957Y-111418D02*
X236841D01*
G01X248537Y-109748D02*
G03X249956Y-112031I2652J66D01*
G01X248537Y-108250D02*
Y-109748D01*
G01X250179Y-106359D02*
G03X248537Y-108249I2747J-4045D01*
G01X256884Y-107368D02*
G03X250178Y-106359I-4153J-4811D01*
G01X253611Y-107689D02*
G03X251080Y-107949I-869J-3992D01*
G01X251081Y-107948D02*
G03X250837Y-110104I805J-1183D01*
G01Y-110106D02*
G03X254306Y-111513I5270J8013D01*
G01X240511Y58500D02*
X238111D01*
G01X240511Y62500D02*
Y58500D01*
G01X238111D02*
Y62500D01*
G01X247322Y58500D02*
X244922D01*
G01X247322Y62500D02*
Y58500D01*
G01X244922D02*
Y62500D01*
G01X252322Y58500D02*
X249922D01*
G01X252322Y62500D02*
Y58500D01*
G01X249922D02*
Y62500D01*
G01X238111D02*
X240511D01*
G01X244922D02*
X247322D01*
G01X249922D02*
X252322D01*
G01X240949Y221250D02*
X241933D01*
Y219281D01*
X240949D01*
Y221250D01*
G01Y228719D02*
X241933D01*
Y226750D01*
X240949D01*
Y228719D01*
G01X246067D02*
X247051D01*
Y226750D01*
X246067D01*
Y228719D01*
G01Y221250D02*
X247051D01*
Y219281D01*
X246067D01*
Y221250D01*
G01X243508D02*
X244492D01*
Y219281D01*
X243508D01*
Y221250D01*
G01X248230Y225772D02*
X239770D01*
G01Y222228D02*
X248230D01*
G01X239770Y226751D02*
X240949D01*
G01X239770Y221249D02*
Y226751D01*
G01X240949Y221249D02*
X239770D01*
G01X248230Y226751D02*
X247051D01*
G01X248230Y221249D02*
Y226751D01*
G01X247051Y221249D02*
X248230D01*
G01X246067Y226751D02*
X241933D01*
G01X243508Y221249D02*
X241933D01*
G01X246067D02*
X244492D01*
G01X255200Y226500D02*
X252800D01*
G01Y230500D02*
X255200D01*
G01X252800Y226500D02*
Y230500D01*
G01Y221500D02*
X255200D01*
G01X252800Y217500D02*
Y221500D01*
G01X255200Y217500D02*
X252800D01*
G01X246000Y236700D02*
Y234300D01*
G01X242000Y236700D02*
X246000D01*
G01X242000Y234300D02*
Y236700D01*
G01X246000Y234300D02*
X242000D01*
G01X251000Y236300D02*
Y238700D01*
G01X255000Y236300D02*
X251000D01*
G01Y238700D02*
X255000D01*
G01X260954Y-116041D02*
Y-107954D01*
G01X254892Y-115895D02*
G03X255001Y-114328I-764J840D01*
G01X269619Y-117484D02*
Y-106797D01*
G01X269620Y-117484D02*
G03X271926I1153J198D01*
G01X266864Y-117375D02*
G03X266002Y-116329I-764J249D01*
G01X262978Y-115462D02*
G03X266002Y-116329I2046J1428D01*
G01X260955Y-116043D02*
G03X264164Y-118351I2956J725D01*
G01X265463Y-118350D02*
X264165D01*
G01X265464Y-118352D02*
G03X266864Y-117374I-24J1525D01*
G01X256906Y-116470D02*
G03X257054Y-113728I-3143J1545D01*
G01X254317Y-118340D02*
G03X256906Y-116470I-1259J4470D01*
G01X262978Y-107954D02*
Y-115463D01*
G01X257054Y-113729D02*
G03X254307Y-111513I-3470J-1490D01*
G01X271969Y-102342D02*
G03I-1194J0D01*
G01X271926Y-106797D02*
G03X269620I-1153J-409D01*
G01X266003Y-107954D02*
X262978D01*
G01X266004Y-107955D02*
G03X266008Y-105932I-177J1012D01*
G01X262978D02*
X266008D01*
G01X262971Y-103419D02*
X262978Y-105932D01*
G01X262972Y-103418D02*
G03X260954Y-103491I-1005J-141D01*
G01Y-105932D02*
Y-103492D01*
G01X259930Y-105932D02*
X260954D01*
G01X259930D02*
G03X259981Y-107955I298J-1005D01*
G01X260954Y-107954D02*
X259982D01*
G01X255606Y-108620D02*
G03X256885Y-107367I599J667D01*
G01X267007Y58500D02*
X264607D01*
G01X267007Y62500D02*
Y58500D01*
G01X264607D02*
Y62500D01*
G01X272007Y58500D02*
X269607D01*
G01D02*
Y62500D01*
G01X264607D02*
X267007D01*
G01X269607D02*
X272007D01*
G01X280567Y112143D02*
G02I-12000J0D01*
G01X257800Y230500D02*
X260200D01*
G01X257800Y226500D02*
Y230500D01*
G01X260200Y226500D02*
X257800D01*
G01X260200Y230500D02*
Y226500D01*
G01X255200Y230500D02*
Y226500D01*
G01Y221500D02*
Y217500D01*
G01X271756Y221850D02*
X269984D01*
G01X268016D02*
X266244D01*
G01X271756Y228150D02*
X266244D01*
G01X263291D02*
X264276D01*
G01X263291Y221850D02*
Y228150D01*
G01X264276Y221850D02*
X263291D01*
G01D02*
X264079Y222638D01*
G01X263291Y228150D02*
X264079Y227362D01*
G01Y222638D02*
X273921D01*
G01Y227362D02*
X264079D01*
G01D02*
Y222638D01*
G01X264276Y227756D02*
X266244D01*
G01D02*
Y230906D01*
G01D02*
X264276D01*
G01D02*
Y227756D01*
G01X268016Y219094D02*
X269984D01*
G01D02*
Y222244D01*
G01D02*
X268016D01*
G01D02*
Y219094D01*
G01X264276D02*
X266244D01*
G01D02*
Y222244D01*
G01D02*
X264276D01*
G01D02*
Y219094D01*
G01X255000Y238700D02*
Y236300D01*
G01X264000Y238700D02*
Y236300D01*
G01X260000Y238700D02*
X264000D01*
G01X260000Y236300D02*
Y238700D01*
G01X264000Y236300D02*
X260000D01*
G01X280567Y255943D02*
G02I-12000J0D01*
G01X290671Y-110842D02*
G03X290703Y-118351I860J-3751D01*
G01X276837Y-114305D02*
G03X278891Y-116297I4069J2141D01*
G01X274529Y-113568D02*
G03X275888Y-116443I5718J944D01*
G01X275887D02*
G03X279572Y-118352I4392J3967D01*
G01X281425Y-118350D02*
X279571D01*
G01X281425D02*
G03X284525Y-117161I0J4636D01*
G01X285201Y-116508D02*
X284524Y-117161D01*
G01X285201Y-116508D02*
G03X283966Y-115211I-695J574D01*
G01X281510Y-116675D02*
G03X283966Y-115212I-989J4453D01*
G01X278889Y-116297D02*
G03X281508Y-116677I1946J4197D01*
G01X271926Y-106797D02*
Y-117484D01*
G01X274529Y-113566D02*
Y-111839D01*
G01X276446Y-112943D02*
G03X276837Y-114305I4162J458D01*
G01X276445Y-112066D02*
Y-112943D01*
G01X283833Y-109274D02*
G03X285403Y-108106I585J852D01*
G01X285402D02*
G03X280919Y-105777I-4776J-3714D01*
G01X279541D02*
X280919D01*
G01X279540D02*
G03X274999Y-109274I1260J-6333D01*
G01X274998D02*
G03X274529Y-111839I9988J-3152D01*
G01X276849Y-109932D02*
G03X276446Y-112066I5467J-2137D01*
G01X280036Y-107542D02*
G03X276849Y-109933I664J-4205D01*
G01X282662Y-108199D02*
G03X280037Y-107539I-2313J-3650D01*
G01X283833Y-109275D02*
G03X282662Y-108202I-9277J-8949D01*
G01X272007Y62500D02*
Y58500D01*
G01X281255D02*
X278855D01*
G01X281255Y62500D02*
Y58500D01*
G01X278855D02*
Y62500D01*
G01X286255Y58500D02*
X283855D01*
G01X286255Y62500D02*
Y58500D01*
G01X283855D02*
Y62500D01*
G01X278855D02*
X281255D01*
G01X283855D02*
X286255D01*
G01X279750Y193300D02*
Y195700D01*
G01X283750Y193300D02*
X279750D01*
G01X283750Y195700D02*
Y193300D01*
G01X279750Y195700D02*
X283750D01*
G01X280700Y183900D02*
X278300D01*
G01X280700Y187900D02*
Y183900D01*
G01X278300Y187900D02*
X280700D01*
G01X278300Y183900D02*
Y187900D01*
G01X277800Y229700D02*
Y233700D01*
G01X280200Y229700D02*
X277800D01*
G01X280200Y233700D02*
Y229700D01*
G01Y216500D02*
X277800D01*
G01X280200Y220500D02*
Y216500D01*
G01X277800Y220500D02*
X280200D01*
G01X277800Y216500D02*
Y220500D01*
G01X282500Y227000D02*
Y235000D01*
G01X287500Y227000D02*
X282500D01*
G01X287500Y235000D02*
Y227000D01*
G01X286300Y216300D02*
Y222700D01*
G01X282700Y216300D02*
X286300D01*
G01X282700Y222700D02*
Y216300D01*
G01X286300Y222700D02*
X282700D01*
G01X274709Y228150D02*
X273724D01*
G01X274709Y221850D02*
Y228150D01*
G01X273724Y221850D02*
X274709D01*
G01X273921Y227362D02*
X274709Y228150D01*
G01X273921Y222638D02*
X274709Y221850D01*
G01X273921Y222638D02*
Y227362D01*
G01X271756Y227756D02*
X273724D01*
G01D02*
Y230906D01*
G01D02*
X271756D01*
G01D02*
Y227756D01*
G01Y219094D02*
X273724D01*
G01D02*
Y222244D01*
G01D02*
X271756D01*
G01D02*
Y219094D01*
G01X277800Y233700D02*
X280200D01*
G01X282500Y235000D02*
X287500D01*
G01X286700Y284500D02*
X284300D01*
G01X286700Y288500D02*
Y284500D01*
G01X284300D02*
Y288500D01*
G01D02*
X286700D01*
G01X294457Y-116619D02*
G03Y-112289I-51J2165D01*
G01X291853Y-116620D02*
X294456D01*
G01X291853Y-112289D02*
G03Y-116619I195J-2165D01*
G01X294165Y-118350D02*
X290701D01*
G01X294165D02*
G03X296471Y-117226I-1088J5161D01*
G01X296473Y-117625D02*
Y-117226D01*
G01X296474Y-117627D02*
G03X298494I1010J185D01*
G01X298495Y-109394D02*
Y-117625D01*
G01X301067Y-108534D02*
Y-106508D01*
G01X301615Y-108534D02*
X301067D01*
G01X301615Y-106508D02*
Y-108534D01*
G01X302461Y-106508D02*
X301615D01*
G01X302461Y-106001D02*
Y-106508D01*
G01X300223Y-106001D02*
X302461D01*
G01X300223Y-106508D02*
Y-106001D01*
G01X301067Y-106508D02*
X300223D01*
G01X305164Y-106001D02*
X304731D01*
G01X305713Y-108544D02*
X305164Y-106001D01*
G01X305171Y-108544D02*
X305713D01*
G01X304889Y-106871D02*
X305171Y-108544D01*
G01X304309D02*
X304889Y-106871D01*
G01X304086Y-108544D02*
X304309D01*
G01X303501Y-106887D02*
X304086Y-108544D01*
G01X303226D02*
X303501Y-106887D01*
G01X302698Y-108544D02*
X303226D01*
G01X303243Y-106001D02*
X302698Y-108544D01*
G01X303648Y-106001D02*
X303243D01*
G01X304192Y-107632D02*
X303648Y-106001D01*
G01X304731D02*
X304192Y-107632D01*
G01X294456Y-112288D02*
X291853D01*
G01X296473Y-110841D02*
Y-109686D01*
G01X296472Y-110841D02*
G03X292878Y-110536I-3256J-17043D01*
G01X292879Y-110535D02*
G03X290670Y-110842I280J-10112D01*
G01X298496Y-109394D02*
G03X295031Y-105933I-3962J-501D01*
G01X291563Y-105932D02*
X295031D01*
G01X291562D02*
G03X289112Y-107085I584J-4421D01*
G01Y-107086D02*
G03X289820Y-108520I585J-603D01*
G01X290987Y-107954D02*
G03X289821Y-108520I1446J-4464D01*
G01X294740Y-107954D02*
X290987D01*
G01X296473Y-109686D02*
G03X294742Y-107955I-1598J133D01*
G01X298503Y58500D02*
X296103D01*
G01X298503Y62500D02*
Y58500D01*
G01X296103D02*
Y62500D01*
G01X303503Y58500D02*
X301103D01*
G01X303503Y62500D02*
Y58500D01*
G01X301103D02*
Y62500D01*
G01X296103D02*
X298503D01*
G01X301103D02*
X303503D01*
G01X307500Y192000D02*
X299500D01*
G01Y197000D02*
X307500D01*
G01X299500Y192000D02*
Y197000D01*
G01X300000Y203800D02*
Y206200D01*
G01X304000Y203800D02*
X300000D01*
G01X304000Y206200D02*
Y203800D01*
G01X300000Y206200D02*
X304000D01*
G01X300000Y199300D02*
Y201700D01*
G01X304000Y199300D02*
X300000D01*
G01X304000Y201700D02*
Y199300D01*
G01X300000Y201700D02*
X304000D01*
G01X303600Y212300D02*
Y223700D01*
G01X298400Y212300D02*
X303600D01*
G01X298400Y223700D02*
Y212300D01*
G01X303300Y212600D02*
Y223400D01*
G01X298700Y212600D02*
X303300D01*
G01X298700Y223400D02*
Y212600D01*
G01X305500Y213400D02*
Y215200D01*
G01X303600Y213400D02*
X305500D01*
G01X303600Y215200D02*
Y213400D01*
G01X305500Y215200D02*
X303600D01*
G01X303300Y212600D02*
X303600Y212300D01*
G01X298700Y212600D02*
X298400Y212300D01*
G01X304600Y215200D02*
Y213400D01*
G01X289800Y230000D02*
Y234000D01*
G01X292200Y230000D02*
X289800D01*
G01X292200Y234000D02*
Y230000D01*
G01X298900Y237200D02*
Y225800D01*
G01X304100D02*
Y237200D01*
G01X298900Y225800D02*
X304100D01*
G01X299200Y236900D02*
Y226100D01*
G01X303800D02*
Y236900D01*
G01X299200Y226100D02*
X303800D01*
G01X304100Y232400D02*
Y230600D01*
G01X306000Y232400D02*
X304100D01*
G01X306000Y230600D02*
Y232400D01*
G01X304100Y230600D02*
X306000D01*
G01X297000Y228700D02*
Y226900D01*
G01X298900Y228700D02*
X297000D01*
G01X298900Y226900D02*
Y228700D01*
G01X297000Y226900D02*
X298900D01*
G01Y225800D02*
X299200Y226100D01*
G01X304100Y225800D02*
X303800Y226100D01*
G01X305100Y230600D02*
Y232400D01*
G01X297900Y226900D02*
Y228700D01*
G01X303600Y223700D02*
X298400D01*
G01X303300Y223400D02*
X298700D01*
G01X298400Y217100D02*
Y218900D01*
G01X296500Y217100D02*
X298400D01*
G01X296500Y218900D02*
Y217100D01*
G01X298400Y218900D02*
X296500D01*
G01X305500Y220800D02*
Y222600D01*
G01X303600Y220800D02*
X305500D01*
G01X303600Y222600D02*
Y220800D01*
G01X305500Y222600D02*
X303600D01*
G01Y223700D02*
X303300Y223400D01*
G01X298400Y223700D02*
X298700Y223400D01*
G01X297400Y218900D02*
Y217100D01*
G01X304600Y222600D02*
Y220800D01*
G01X289800Y234000D02*
X292200D01*
G01X304100Y237200D02*
X298900D01*
G01X303800Y236900D02*
X299200D01*
G01X297000Y236100D02*
Y234300D01*
G01X298900Y236100D02*
X297000D01*
G01X298900Y234300D02*
Y236100D01*
G01X297000Y234300D02*
X298900D01*
G01X299200Y236900D02*
X298900Y237200D01*
G01X303800Y236900D02*
X304100Y237200D01*
G01X297900Y234300D02*
Y236100D01*
G01X291200Y284500D02*
X288800D01*
G01D02*
Y288500D01*
G01X291200D02*
Y284500D01*
G01X298500Y292000D02*
Y284000D01*
G01X293500D02*
Y292000D01*
G01X298500Y284000D02*
X293500D01*
G01X306000Y292000D02*
Y284000D01*
G01X301000D02*
Y292000D01*
G01X306000Y284000D02*
X301000D01*
G01X288800Y288500D02*
X291200D01*
G01X293500Y292000D02*
X298500D01*
G01X301000D02*
X306000D01*
G01X302700Y319800D02*
Y322200D01*
G01X306700Y319800D02*
X302700D01*
G01Y331700D02*
X306700D01*
G01X302700Y329300D02*
Y331700D01*
G01X306700Y329300D02*
X302700D01*
G01Y336200D02*
X306700D01*
G01X302700Y333800D02*
Y336200D01*
G01X306700Y333800D02*
X302700D01*
G01Y324800D02*
Y327200D01*
G01X306700Y324800D02*
X302700D01*
G01Y327200D02*
X306700D01*
G01X302700Y322200D02*
X306700D01*
G01X312200Y1981D02*
X310200Y-19D01*
G01X312200Y36281D02*
Y1981D01*
G01X307500Y197000D02*
Y192000D01*
G01X313500Y292000D02*
Y284000D01*
G01X308500D02*
Y292000D01*
G01X313500Y284000D02*
X308500D01*
G01X316700Y284800D02*
X320300D01*
G01X316700Y291200D02*
Y284800D01*
G01X320300D02*
Y291200D01*
G01X323300Y286000D02*
Y290000D01*
G01X325700Y286000D02*
X323300D01*
G01Y290000D02*
X325700D01*
G01X308500Y292000D02*
X313500D01*
G01X320300Y291200D02*
X316700D01*
G01X306700Y322200D02*
Y319800D01*
G01Y331700D02*
Y329300D01*
G01Y336200D02*
Y333800D01*
G01Y327200D02*
Y324800D01*
G01X317300Y388000D02*
Y392000D01*
G01X319700Y388000D02*
X317300D01*
G01X319700Y392000D02*
Y388000D01*
G01X316000Y375000D02*
Y383000D01*
G01X321000Y375000D02*
X316000D01*
G01X321000Y383000D02*
Y375000D01*
G01X316000Y383000D02*
X321000D01*
G01X317300Y392000D02*
X319700D01*
G01X337000Y226700D02*
Y224300D01*
G01X333000Y226700D02*
X337000D01*
G01X333000Y224300D02*
Y226700D01*
G01X337000Y224300D02*
X333000D01*
G01Y219800D02*
Y222200D01*
G01X337000Y219800D02*
X333000D01*
G01X337000Y222200D02*
Y219800D01*
G01X333000Y222200D02*
X337000D01*
G01X332300Y255200D02*
X334700D01*
G01X332300Y251200D02*
Y255200D01*
G01X334700Y251200D02*
X332300D01*
G01X334700Y255200D02*
Y251200D01*
G01X325700Y290000D02*
Y286000D01*
G01X336200Y286500D02*
X333800D01*
G01X336200Y290500D02*
Y286500D01*
G01X333800Y290500D02*
X336200D01*
G01X333800Y286500D02*
Y290500D01*
G01X340700Y286500D02*
X338300D01*
G01X340700Y290500D02*
Y286500D01*
G01X338300Y290500D02*
X340700D01*
G01X338300Y286500D02*
Y290500D01*
G01X325700Y319300D02*
Y321700D01*
G01X329700Y319300D02*
X325700D01*
G01X329700Y321700D02*
Y319300D01*
G01X325700Y328300D02*
Y330700D01*
G01X329700Y328300D02*
X325700D01*
G01X329700Y330700D02*
Y328300D01*
G01X325700Y330700D02*
X329700D01*
G01X325700Y332800D02*
Y335200D01*
G01X329700Y332800D02*
X325700D01*
G01X329700Y335200D02*
Y332800D01*
G01X325700Y335200D02*
X329700D01*
G01X325700Y337300D02*
Y339700D01*
G01X329700Y337300D02*
X325700D01*
G01X329700Y339700D02*
Y337300D01*
G01X325700Y323800D02*
Y326200D01*
G01X329700Y323800D02*
X325700D01*
G01X329700Y326200D02*
Y323800D01*
G01X325700Y326200D02*
X329700D01*
G01X325700Y321700D02*
X329700D01*
G01X325700Y346300D02*
Y348700D01*
G01X329700Y346300D02*
X325700D01*
G01X329700Y348700D02*
Y346300D01*
G01X325700Y348700D02*
X329700D01*
G01X325700Y339700D02*
X329700D01*
G01X325700Y341800D02*
Y344200D01*
G01X329700Y341800D02*
X325700D01*
G01X329700Y344200D02*
Y341800D01*
G01X325700Y344200D02*
X329700D01*
G01X328500Y408200D02*
Y405800D01*
G01X324500D02*
Y408200D01*
G01X328500Y405800D02*
X324500D01*
G01X336250Y395650D02*
Y393750D01*
G01X337350Y395650D02*
X336250D01*
G01X337350Y393750D02*
Y395650D01*
G01X336250Y393750D02*
X337350D01*
G01X324500Y408200D02*
X328500D01*
G01X338500Y410700D02*
Y408300D01*
G01X334500Y410700D02*
X338500D01*
G01X334500Y408300D02*
Y410700D01*
G01X338500Y408300D02*
X334500D01*
G01X350800Y137500D02*
X353200D01*
G01X350800Y133500D02*
Y137500D01*
G01X353200Y133500D02*
X350800D01*
G01X353200Y137500D02*
Y133500D01*
G01X343500Y130500D02*
Y138500D01*
G01X348500Y130500D02*
X343500D01*
G01X348500Y138500D02*
Y130500D01*
G01X343500Y138500D02*
X348500D01*
G01X349300Y179000D02*
Y183000D01*
G01X351700Y179000D02*
X349300D01*
G01X351700Y183000D02*
Y179000D01*
G01X349300Y183000D02*
X351700D01*
G01X353400Y191949D02*
Y194349D01*
G01X357400Y191949D02*
X353400D01*
G01X357400Y194349D02*
Y191949D01*
G01X353400Y194349D02*
X357400D01*
G01X353400Y187449D02*
Y189849D01*
G01X357400Y187449D02*
X353400D01*
G01X357400Y189849D02*
Y187449D01*
G01X353400Y189849D02*
X357400D01*
G01X342000Y224300D02*
Y226700D01*
G01X346000Y224300D02*
X342000D01*
G01X346000Y226700D02*
Y224300D01*
G01X342000Y226700D02*
X346000D01*
G01Y222200D02*
Y219800D01*
G01X342000Y222200D02*
X346000D01*
G01X342000Y219800D02*
Y222200D01*
G01X346000Y219800D02*
X342000D01*
G01X345800Y233500D02*
Y237500D01*
G01X348200Y233500D02*
X345800D01*
G01X348200Y237500D02*
Y233500D01*
G01X345800Y237500D02*
X348200D01*
G01X342800Y290500D02*
X345200D01*
G01X342800Y286500D02*
Y290500D01*
G01X345200Y286500D02*
X342800D01*
G01X345200Y290500D02*
Y286500D01*
G01X347300Y290500D02*
X349700D01*
G01X347300Y286500D02*
Y290500D01*
G01X349700Y286500D02*
X347300D01*
G01X349700Y290500D02*
Y286500D01*
G01X346500Y335800D02*
Y338200D01*
G01X350500Y335800D02*
X346500D01*
G01X350500Y338200D02*
Y335800D01*
G01X346500Y331300D02*
Y333700D01*
G01X350500Y331300D02*
X346500D01*
G01X350500Y333700D02*
Y331300D01*
G01X346500Y333700D02*
X350500D01*
G01X346500Y326800D02*
Y329200D01*
G01X350500Y326800D02*
X346500D01*
G01X350500Y329200D02*
Y326800D01*
G01X346500Y329200D02*
X350500D01*
G01X346500Y322300D02*
Y324700D01*
G01X350500Y322300D02*
X346500D01*
G01X350500Y324700D02*
Y322300D01*
G01X346500Y324700D02*
X350500D01*
G01X346500Y338200D02*
X350500D01*
G01X346500Y340300D02*
Y342700D01*
G01X350500Y340300D02*
X346500D01*
G01X350500Y342700D02*
Y340300D01*
G01X346500Y342700D02*
X350500D01*
G01X357500Y386900D02*
Y390500D01*
G01X351100Y386900D02*
X357500D01*
G01X351100Y390500D02*
Y386900D01*
G01X356300Y395400D02*
Y393000D01*
G01X352300Y395400D02*
X356300D01*
G01X352300Y393000D02*
Y395400D01*
G01X356300Y393000D02*
X352300D01*
G01Y402000D02*
Y404400D01*
G01X356300Y402000D02*
X352300D01*
G01X356300Y404400D02*
Y402000D01*
G01X352300Y404400D02*
X356300D01*
G01Y408900D02*
Y406500D01*
G01X352300D02*
Y408900D01*
G01X356300Y406500D02*
X352300D01*
G01Y397500D02*
Y399900D01*
G01X356300Y397500D02*
X352300D01*
G01X356300Y399900D02*
Y397500D01*
G01X352300Y399900D02*
X356300D01*
G01X357500Y390500D02*
X351100D01*
G01X352300Y408900D02*
X356300D01*
G01X355300Y418500D02*
Y420900D01*
G01X359300Y418500D02*
X355300D01*
G01Y420900D02*
X359300D01*
G01X358000Y414200D02*
Y411800D01*
G01X354000Y414200D02*
X358000D01*
G01X354000Y411800D02*
Y414200D01*
G01X358000Y411800D02*
X354000D01*
G01X375800Y81000D02*
X378200D01*
G01X375800Y77000D02*
Y81000D01*
G01X378200Y77000D02*
X375800D01*
G01X378800Y92200D02*
X375200D01*
G01Y85800D02*
X378800D01*
G01X375200Y92200D02*
Y85800D01*
G01X380500Y103500D02*
X372500D01*
G01Y108500D02*
X380500D01*
G01X372500Y103500D02*
Y108500D01*
G01X367700Y137700D02*
Y141300D01*
G01X361300Y137700D02*
X367700D01*
G01X361300Y141300D02*
Y137700D01*
G01X367700Y141300D02*
X361300D01*
G01X370500Y170800D02*
Y173200D01*
G01X374500Y170800D02*
X370500D01*
G01X374500Y173200D02*
Y170800D01*
G01X370500Y173200D02*
X374500D01*
G01X361000Y215800D02*
Y218200D01*
G01X365000Y215800D02*
X361000D01*
G01X365000Y218200D02*
Y215800D01*
G01X361000Y218200D02*
X365000D01*
G01X368500Y220500D02*
X360500D01*
G01X368500Y225500D02*
Y220500D01*
G01X360500Y225500D02*
X368500D01*
G01X360500Y220500D02*
Y225500D01*
G01X363700Y294500D02*
Y302500D01*
G01X368700Y294500D02*
X363700D01*
G01X368700Y302500D02*
Y294500D01*
G01X363700Y302500D02*
X368700D01*
G01X374500Y322300D02*
Y324700D01*
G01X378500Y322300D02*
X374500D01*
G01Y324700D02*
X378500D01*
G01X374500Y329200D02*
X378500D01*
G01X374500Y326800D02*
Y329200D01*
G01X378500Y326800D02*
X374500D01*
G01Y333700D02*
X378500D01*
G01X374500Y331300D02*
Y333700D01*
G01X378500Y331300D02*
X374500D01*
G01Y335800D02*
Y338200D01*
G01X378500Y335800D02*
X374500D01*
G01Y342700D02*
X378500D01*
G01X374500Y340300D02*
Y342700D01*
G01X378500Y340300D02*
X374500D01*
G01Y338200D02*
X378500D01*
G01X359300Y420900D02*
Y418500D01*
G01X378200Y81000D02*
Y77000D01*
G01X378800Y85800D02*
Y92200D01*
G01X380500Y108500D02*
Y103500D01*
G01X391729Y130561D02*
Y128161D01*
G01X387729D02*
Y130561D01*
G01X391729Y128161D02*
X387729D01*
G01Y130561D02*
X391729D01*
G01X376000Y129500D02*
Y137500D01*
G01X381000Y129500D02*
X376000D01*
G01Y137500D02*
X381000D01*
G01D02*
Y129500D01*
G01X397067Y154047D02*
X393067D01*
G01Y151647D02*
X397067D01*
G01X393067Y154047D02*
Y151647D01*
G01X389129Y147710D02*
X393129D01*
G01X389129Y150110D02*
Y147710D01*
G01X393129Y150110D02*
X389129D01*
G01X393129Y147710D02*
Y150110D01*
G01X388530Y175700D02*
Y173300D01*
G01X384530Y175700D02*
X388530D01*
G01X384530Y173300D02*
Y175700D01*
G01X388530Y173300D02*
X384530D01*
G01X391898Y176501D02*
Y172501D01*
G01X394298Y176501D02*
X391898D01*
G01Y172501D02*
X394298D01*
G01X393067Y163458D02*
X397067D01*
G01X393067Y165858D02*
Y163458D01*
G01X397067Y165858D02*
X393067D01*
G01Y185543D02*
Y183143D01*
G01D02*
X397067D01*
G01Y185543D02*
X393067D01*
G01X397067Y201291D02*
X393067D01*
G01D02*
Y198891D01*
G01D02*
X397067D01*
G01X397066Y205228D02*
X393066D01*
G01D02*
Y202828D01*
G01D02*
X397066D01*
G01X391898Y207933D02*
X394298D01*
G01X391898Y211933D02*
Y207933D01*
G01X394298Y211933D02*
X391898D01*
G01X389129Y214639D02*
X393129D01*
G01X389129Y217039D02*
Y214639D01*
G01X393129D02*
Y217039D01*
G01D02*
X389129D01*
G01X390700Y251100D02*
Y255100D01*
G01X393100Y251100D02*
X390700D01*
G01X393100Y255100D02*
Y251100D01*
G01X390700Y255100D02*
X393100D01*
G01X384800Y251100D02*
Y255100D01*
G01X387200Y251100D02*
X384800D01*
G01X387200Y255100D02*
Y251100D01*
G01X384800Y255100D02*
X387200D01*
G01X378900Y251100D02*
Y255100D01*
G01X381300Y251100D02*
X378900D01*
G01X381300Y255100D02*
Y251100D01*
G01X378900Y255100D02*
X381300D01*
G01X379400Y308000D02*
Y310400D01*
G01X383400Y308000D02*
X379400D01*
G01X383400Y310400D02*
Y308000D01*
G01X379400Y310400D02*
X383400D01*
G01X389200Y308000D02*
Y310400D01*
G01X393200Y308000D02*
X389200D01*
G01X393200Y310400D02*
Y308000D01*
G01X389200Y310400D02*
X393200D01*
G01X378500Y324700D02*
Y322300D01*
G01Y329200D02*
Y326800D01*
G01Y333700D02*
Y331300D01*
G01Y338200D02*
Y335800D01*
G01Y342700D02*
Y340300D01*
G01X388000Y377000D02*
Y374600D01*
G01X384000Y377000D02*
X388000D01*
G01X384000Y374600D02*
Y377000D01*
G01X388000Y374600D02*
X384000D01*
G01X388000Y382200D02*
Y379800D01*
G01X384000Y382200D02*
X388000D01*
G01X384000Y379800D02*
Y382200D01*
G01X388000Y379800D02*
X384000D01*
G01X395835Y148942D02*
Y144942D01*
G01X398235D02*
Y148942D01*
G01X395835Y144942D02*
X398235D01*
G01X403710Y141067D02*
Y137067D01*
G01X406110Y141067D02*
X403710D01*
G01X406110Y137067D02*
Y141067D01*
G01X403710Y137067D02*
X406110D01*
G01X402173Y144941D02*
Y148941D01*
G01X399773Y144941D02*
X402173D01*
G01X399773Y148941D02*
Y144941D01*
G01X397067Y151647D02*
Y154047D01*
G01X402173Y160689D02*
Y164689D01*
G01X399773Y160689D02*
X402173D01*
G01X399773Y164689D02*
Y160689D01*
G01X398235Y148942D02*
X395835D01*
G01X402173Y148941D02*
X399773D01*
G01X412816Y161921D02*
X408816D01*
G01Y159521D02*
X412816D01*
G01X408816Y161921D02*
Y159521D01*
G01X403710Y164690D02*
Y160690D01*
G01X406110D02*
Y164690D01*
G01X403710Y160690D02*
X406110D01*
G01X412816Y157984D02*
X408816D01*
G01Y155584D02*
X412816D01*
G01X408816Y157984D02*
Y155584D01*
G01X399773Y156816D02*
Y152816D01*
G01X402173Y156816D02*
X399773D01*
G01X402173Y152816D02*
Y156816D01*
G01X399773Y152816D02*
X402173D01*
G01X408878Y147710D02*
Y150110D01*
G01D02*
X404878D01*
G01D02*
Y147710D01*
G01D02*
X408878D01*
G01X409900Y176200D02*
X413900D01*
G01X409900Y173800D02*
Y176200D01*
G01X413900Y173800D02*
X409900D01*
G01X402173Y164689D02*
X399773D01*
G01X394298Y172501D02*
Y176501D01*
G01X397067Y163458D02*
Y165858D01*
G01X400941Y179206D02*
X404941D01*
G01X400941Y181606D02*
Y179206D01*
G01X404941D02*
Y181606D01*
G01X406110Y164690D02*
X403710D01*
G01X408878Y167395D02*
Y169795D01*
G01D02*
X404878D01*
G01D02*
Y167395D01*
G01D02*
X408878D01*
G01X403710Y192186D02*
X406110D01*
G01D02*
Y196186D01*
G01D02*
X403710D01*
G01D02*
Y192186D01*
G01X401004Y191017D02*
Y193417D01*
G01D02*
X397004D01*
G01D02*
Y191017D01*
G01D02*
X401004D01*
G01X412815Y197354D02*
X408815D01*
G01D02*
Y194954D01*
G01D02*
X412815D01*
G01X404941Y181606D02*
X400941D01*
G01X397067Y183143D02*
Y185543D01*
G01Y198891D02*
Y201291D01*
G01X397066Y202828D02*
Y205228D01*
G01X394298Y207933D02*
Y211933D01*
G01X406500Y222700D02*
Y220300D01*
G01X402500Y222700D02*
X406500D01*
G01X402500Y220300D02*
Y222700D01*
G01X406500Y220300D02*
X402500D01*
G01X397200Y227600D02*
Y237400D01*
G01X409800Y227600D02*
X397200D01*
G01X409800Y237400D02*
Y227600D01*
G01X397200Y237400D02*
X409800D01*
G01X402500Y251100D02*
Y255100D01*
G01X404900Y251100D02*
X402500D01*
G01X404900Y255100D02*
Y251100D01*
G01X402500Y255100D02*
X404900D01*
G01X396600Y251100D02*
Y255100D01*
G01X399000Y251100D02*
X396600D01*
G01X399000Y255100D02*
Y251100D01*
G01X396600Y255100D02*
X399000D01*
G01X408100Y251100D02*
Y255100D01*
G01X410500Y251100D02*
X408100D01*
G01X410500Y255100D02*
Y251100D01*
G01X408100Y255100D02*
X410500D01*
G01X397400Y322700D02*
Y325100D01*
G01X401400Y322700D02*
X397400D01*
G01X401400Y325100D02*
Y322700D01*
G01X397400Y325100D02*
X401400D01*
G01X397400Y327900D02*
Y330300D01*
G01X401400Y327900D02*
X397400D01*
G01X401400Y330300D02*
Y327900D01*
G01X397400Y330300D02*
X401400D01*
G01X399200Y343000D02*
X396800D01*
G01X399200Y347000D02*
Y343000D01*
G01X396800Y347000D02*
X399200D01*
G01X396800Y343000D02*
Y347000D01*
G01X427000Y71800D02*
Y74200D01*
G01X431000Y71800D02*
X427000D01*
G01Y74200D02*
X431000D01*
G01X428700Y92000D02*
X426300D01*
G01D02*
Y96000D01*
G01X428800Y83700D02*
X425200D01*
G01Y77300D02*
X428800D01*
G01X425200Y83700D02*
Y77300D01*
G01X426300Y96000D02*
X428700D01*
G01X419458Y141004D02*
X421858D01*
G01D02*
Y145004D01*
G01D02*
X419458D01*
G01D02*
Y141004D01*
G01Y164689D02*
Y160689D01*
G01D02*
X421858D01*
G01D02*
Y164689D01*
G01X412752Y147710D02*
X416752D01*
G01X412752Y150110D02*
Y147710D01*
G01X416752Y150110D02*
X412752D01*
G01X416752Y147710D02*
Y150110D01*
G01Y151647D02*
Y154047D01*
G01D02*
X412752D01*
G01D02*
Y151647D01*
G01D02*
X416752D01*
G01X421858Y152878D02*
X419458D01*
G01D02*
Y148878D01*
G01D02*
X421858D01*
G01D02*
Y152878D01*
G01X423395Y160690D02*
X425795D01*
G01D02*
Y164690D01*
G01X423395D02*
Y160690D01*
G01X420627Y157984D02*
Y155584D01*
G01D02*
X424627D01*
G01D02*
Y157984D01*
G01D02*
X420627D01*
G01X417921Y160752D02*
X415521D01*
G01D02*
Y156752D01*
G01D02*
X417921D01*
G01D02*
Y160752D01*
G01X412816Y159521D02*
Y161921D01*
G01Y155584D02*
Y157984D01*
G01X413900Y176200D02*
Y173800D01*
G01X424000Y176200D02*
Y173800D01*
G01X420000Y176200D02*
X424000D01*
G01X420000Y173800D02*
Y176200D01*
G01X424000Y173800D02*
X420000D01*
G01X421858Y164689D02*
X419458D01*
G01X420626Y179206D02*
X424626D01*
G01X420626Y181606D02*
Y179206D01*
G01X424626D02*
Y181606D01*
G01X425795Y164690D02*
X423395D01*
G01X415521Y164627D02*
X417921D01*
G01D02*
Y168627D01*
G01D02*
X415521D01*
G01D02*
Y164627D01*
G01X424626Y167395D02*
Y169795D01*
G01D02*
X420626D01*
G01D02*
Y167395D01*
G01D02*
X424626D01*
G01X413984Y164626D02*
Y168626D01*
G01X411584Y164626D02*
X413984D01*
G01X411584Y168626D02*
Y164626D01*
G01X413984Y168626D02*
X411584D01*
G01X424626Y181606D02*
X420626D01*
G01X419458Y188312D02*
Y184312D01*
G01X421858Y188312D02*
X419458D01*
G01X421858Y184312D02*
Y188312D01*
G01X419458Y184312D02*
X421858D01*
G01X415521Y196123D02*
X417921D01*
G01D02*
Y200123D01*
G01X415521D02*
Y196123D01*
G01X412815Y194954D02*
Y197354D01*
G01X423395Y215871D02*
Y211871D01*
G01X425795D02*
Y215871D01*
G01X423395Y211871D02*
X425795D01*
G01X417921Y200123D02*
X415521D01*
G01X412753Y205228D02*
Y202828D01*
G01D02*
X416753D01*
G01D02*
Y205228D01*
G01D02*
X412753D01*
G01X425795Y215871D02*
X423395D01*
G01X419700Y251100D02*
Y255100D01*
G01X422100Y251100D02*
X419700D01*
G01X422100Y255100D02*
Y251100D01*
G01X419700Y255100D02*
X422100D01*
G01X413800Y251100D02*
Y255100D01*
G01X416200Y251100D02*
X413800D01*
G01X416200Y255100D02*
Y251100D01*
G01X413800Y255100D02*
X416200D01*
G01X412700Y283000D02*
Y288000D01*
G01X420700Y283000D02*
X412700D01*
G01X420700Y288000D02*
Y283000D01*
G01X412700Y296100D02*
X420700D01*
G01X412700Y291100D02*
Y296100D01*
G01X420700Y291100D02*
X412700D01*
G01X420700Y296100D02*
Y291100D01*
G01X412700Y288000D02*
X420700D01*
G01X418200Y343000D02*
X415800D01*
G01X418200Y347000D02*
Y343000D01*
G01X415800Y347000D02*
X418200D01*
G01X415800Y343000D02*
Y347000D01*
G01X425200Y394200D02*
X422800D01*
G01X425200Y398200D02*
Y394200D01*
G01X422800Y398200D02*
X425200D01*
G01X422800Y394200D02*
Y398200D01*
G01X422500Y405300D02*
Y407700D01*
G01X426500Y405300D02*
X422500D01*
G01X426500Y407700D02*
Y405300D01*
G01X422500Y407700D02*
X426500D01*
G01X422500Y410300D02*
Y412700D01*
G01X426500Y410300D02*
X422500D01*
G01X426500Y412700D02*
Y410300D01*
G01X422500Y412700D02*
X426500D01*
G01X431000Y74200D02*
Y71800D01*
G01X433200Y92000D02*
X430800D01*
G01X433200Y96000D02*
Y92000D01*
G01X430800D02*
Y96000D01*
G01X428700D02*
Y92000D01*
G01X428800Y77300D02*
Y83700D01*
G01X430800Y96000D02*
X433200D01*
G01X440300Y108000D02*
Y112000D01*
G01X442700Y108000D02*
X440300D01*
G01X442700Y112000D02*
Y108000D01*
G01X435800D02*
Y112000D01*
G01X438200Y108000D02*
X435800D01*
G01X438200Y112000D02*
Y108000D01*
G01X440300Y112000D02*
X442700D01*
G01X435800D02*
X438200D01*
G01X439143Y137130D02*
Y133130D01*
G01X441543Y137130D02*
X439143D01*
G01X441543Y133130D02*
Y137130D01*
G01X439143Y133130D02*
X441543D01*
G01X445480Y141004D02*
Y145004D01*
G01X443080Y141004D02*
X445480D01*
G01X443080Y145004D02*
Y141004D01*
G01X445480Y145004D02*
X443080D01*
G01X435206Y148942D02*
Y144942D01*
G01X437606D02*
Y148942D01*
G01X435206Y144942D02*
X437606D01*
G01X429700Y144500D02*
X432100D01*
G01D02*
Y148500D01*
G01X429700D02*
Y144500D01*
G01X431700Y155000D02*
X429300D01*
G01X431700Y159000D02*
Y155000D01*
G01X429300Y159000D02*
X431700D01*
G01X429300Y155000D02*
Y159000D01*
G01X441543Y156752D02*
Y160752D01*
G01X439143Y156752D02*
X441543D01*
G01X439143Y160752D02*
Y156752D01*
G01X441543Y160752D02*
X439143D01*
G01X443080Y156753D02*
X445480D01*
G01D02*
Y160753D01*
G01D02*
X443080D01*
G01D02*
Y156753D01*
G01X435206Y164690D02*
Y160690D01*
G01X437606D02*
Y164690D01*
G01X435206Y160690D02*
X437606D01*
G01Y148942D02*
X435206D01*
G01X437606Y152815D02*
Y156815D01*
G01X435206Y152815D02*
X437606D01*
G01X435206Y156815D02*
Y152815D01*
G01X437606Y156815D02*
X435206D01*
G01X432100Y148500D02*
X429700D01*
G01X429300Y169000D02*
X431700D01*
G01X429300Y165000D02*
Y169000D01*
G01X431700Y165000D02*
X429300D01*
G01X431700Y169000D02*
Y165000D01*
G01X436400Y175300D02*
Y172900D01*
G01X432400Y175300D02*
X436400D01*
G01X432400Y172900D02*
Y175300D01*
G01X436400Y172900D02*
X432400D01*
G01X429400Y179600D02*
Y183600D01*
G01X431800Y179600D02*
X429400D01*
G01X431800Y183600D02*
Y179600D01*
G01X442411Y174300D02*
Y176700D01*
G01X446411Y174300D02*
X442411D01*
G01Y176700D02*
X446411D01*
G01X448249Y169795D02*
X444249D01*
G01Y167395D02*
X448249D01*
G01X444249Y169795D02*
Y167395D01*
G01Y165858D02*
Y163458D01*
G01D02*
X448249D01*
G01Y165858D02*
X444249D01*
G01X441543Y168626D02*
X439143D01*
G01D02*
Y164626D01*
G01D02*
X441543D01*
G01D02*
Y168626D01*
G01X436375Y181606D02*
Y179206D01*
G01D02*
X440375D01*
G01D02*
Y181606D01*
G01X437606Y164690D02*
X435206D01*
G01X443080Y184374D02*
Y180374D01*
G01X445480D02*
Y184374D01*
G01X443080Y180374D02*
X445480D01*
G01X429400Y183600D02*
X431800D01*
G01X444311Y191017D02*
Y193417D01*
G01D02*
X440311D01*
G01D02*
Y191017D01*
G01D02*
X444311D01*
G01X440375Y181606D02*
X436375D01*
G01X429806Y189749D02*
X432206D01*
G01D02*
Y193749D01*
G01D02*
X429806D01*
G01D02*
Y189749D01*
G01X445480Y184374D02*
X443080D01*
G01X431200Y198800D02*
X428800D01*
G01X431200Y202800D02*
Y198800D01*
G01X428800D02*
Y202800D01*
G01D02*
X431200D01*
G01X445585Y223200D02*
X449585D01*
G01X445585Y220800D02*
Y223200D01*
G01X449585Y220800D02*
X445585D01*
G01X439143Y219808D02*
Y215808D01*
G01X441543D02*
Y219808D01*
G01X439143Y215808D02*
X441543D01*
G01Y219808D02*
X439143D01*
G01X436200Y242000D02*
X433800D01*
G01X436200Y246000D02*
Y242000D01*
G01X433800Y246000D02*
X436200D01*
G01X433800Y242000D02*
Y246000D01*
G01X445200Y242000D02*
X442800D01*
G01X445200Y246000D02*
Y242000D01*
G01X442800Y246000D02*
X445200D01*
G01X442800Y242000D02*
Y246000D01*
G01X438300D02*
X440700D01*
G01X438300Y242000D02*
Y246000D01*
G01X440700Y242000D02*
X438300D01*
G01X440700Y246000D02*
Y242000D01*
G01X432500Y296300D02*
Y298700D01*
G01X436500Y296300D02*
X432500D01*
G01X436500Y298700D02*
Y296300D01*
G01X432500Y298700D02*
X436500D01*
G01X439500Y387700D02*
Y385300D01*
G01X435500Y387700D02*
X439500D01*
G01X435500Y385300D02*
Y387700D01*
G01X439500Y385300D02*
X435500D01*
G01Y395300D02*
Y397700D01*
G01X439500Y395300D02*
X435500D01*
G01X439500Y397700D02*
Y395300D01*
G01X435500Y397700D02*
X439500D01*
G01Y407700D02*
Y405300D01*
G01X435500D02*
Y407700D01*
G01X439500Y405300D02*
X435500D01*
G01X439500Y412700D02*
Y410300D01*
G01X435500Y412700D02*
X439500D01*
G01X435500Y410300D02*
Y412700D01*
G01X439500Y410300D02*
X435500D01*
G01Y407700D02*
X439500D01*
G01X451800Y118000D02*
X454200D01*
G01X451800Y114000D02*
Y118000D01*
G01X454200Y114000D02*
X451800D01*
G01X454200Y118000D02*
Y114000D01*
G01X457300Y118000D02*
X459700D01*
G01X457300Y114000D02*
Y118000D01*
G01X459700Y114000D02*
X457300D01*
G01X459700Y118000D02*
Y114000D01*
G01X459996Y128024D02*
X463996D01*
G01X459996Y130424D02*
Y128024D01*
G01X450954Y137066D02*
X453354D01*
G01D02*
Y141066D01*
G01D02*
X450954D01*
G01D02*
Y137066D01*
G01X460059Y139835D02*
Y142235D01*
G01D02*
X456059D01*
G01D02*
Y139835D01*
G01D02*
X460059D01*
G01X463996Y130424D02*
X459996D01*
G01X452186Y143773D02*
Y146173D01*
G01X448186Y143773D02*
X452186D01*
G01X448186Y146173D02*
Y143773D01*
G01X458828Y156816D02*
Y152816D01*
G01X461228Y156816D02*
X458828D01*
G01X461228Y152816D02*
Y156816D01*
G01X458828Y152816D02*
X461228D01*
G01X449417Y160752D02*
X447017D01*
G01D02*
Y156752D01*
G01D02*
X449417D01*
G01D02*
Y160752D01*
G01X452186Y146173D02*
X448186D01*
G01X451411Y174300D02*
Y176700D01*
G01X455411Y174300D02*
X451411D01*
G01X455411Y176700D02*
Y174300D01*
G01X451411Y176700D02*
X455411D01*
G01X446411D02*
Y174300D01*
G01X448249Y167395D02*
Y169795D01*
G01X453354Y168626D02*
X450954D01*
G01D02*
Y164626D01*
G01D02*
X453354D01*
G01D02*
Y168626D01*
G01X448249Y163458D02*
Y165858D01*
G01X459996Y167395D02*
X463996D01*
G01X459996Y169795D02*
Y167395D01*
G01X463996Y169795D02*
X459996D01*
G01X450954Y180375D02*
X453354D01*
G01D02*
Y184375D01*
G01X450954D02*
Y180375D01*
G01X447017Y184374D02*
Y180374D01*
G01X449417D02*
Y184374D01*
G01X447017Y180374D02*
X449417D01*
G01X459997Y197354D02*
Y194954D01*
G01D02*
X463997D01*
G01Y197354D02*
X459997D01*
G01X463997Y193417D02*
X459997D01*
G01Y191017D02*
X463997D01*
G01X459997Y193417D02*
Y191017D01*
G01X462765Y188312D02*
Y184312D01*
G01X465165Y188312D02*
X462765D01*
G01Y184312D02*
X465165D01*
G01X447016Y196185D02*
Y192185D01*
G01X449416Y196185D02*
X447016D01*
G01X449416Y192185D02*
Y196185D01*
G01X447016Y192185D02*
X449416D01*
G01X453354Y184375D02*
X450954D01*
G01X449417Y184374D02*
X447017D01*
G01X456059Y183143D02*
X460059D01*
G01X456059Y185543D02*
Y183143D01*
G01X460059Y185543D02*
X456059D01*
G01X460059Y183143D02*
Y185543D01*
G01X460060Y189480D02*
X456060D01*
G01X460060Y187080D02*
Y189480D01*
G01X456060Y187080D02*
X460060D01*
G01X456060Y189480D02*
Y187080D01*
G01X448185Y206765D02*
X452185D01*
G01X448185Y209165D02*
Y206765D01*
G01X452185Y209165D02*
X448185D01*
G01X452185Y206765D02*
Y209165D01*
G01X449585Y223200D02*
Y220800D01*
G01X460800Y246000D02*
X463200D01*
G01X460800Y242000D02*
Y246000D01*
G01X463200Y242000D02*
X460800D01*
G01X458700D02*
X456300D01*
G01X458700Y246000D02*
Y242000D01*
G01X456300Y246000D02*
X458700D01*
G01X456300Y242000D02*
Y246000D01*
G01X449700Y242000D02*
X447300D01*
G01X449700Y246000D02*
Y242000D01*
G01X447300Y246000D02*
X449700D01*
G01X447300Y242000D02*
Y246000D01*
G01X451800D02*
X454200D01*
G01X451800Y242000D02*
Y246000D01*
G01X454200Y242000D02*
X451800D01*
G01X454200Y246000D02*
Y242000D01*
G01X452500Y283300D02*
Y285700D01*
G01X456500Y283300D02*
X452500D01*
G01X456500Y285700D02*
Y283300D01*
G01Y280700D02*
Y278300D01*
G01X452500Y280700D02*
X456500D01*
G01X452500Y278300D02*
Y280700D01*
G01X456500Y278300D02*
X452500D01*
G01Y285700D02*
X456500D01*
G01X452500Y288300D02*
Y290700D01*
G01X456500Y288300D02*
X452500D01*
G01X456500Y290700D02*
Y288300D01*
G01X452500Y290700D02*
X456500D01*
G01Y295700D02*
Y293300D01*
G01X452500Y295700D02*
X456500D01*
G01X452500Y293300D02*
Y295700D01*
G01X456500Y293300D02*
X452500D01*
G01X461500Y388300D02*
Y390700D01*
G01X465500Y388300D02*
X461500D01*
G01Y395200D02*
X465500D01*
G01X461500Y392800D02*
Y395200D01*
G01X465500Y392800D02*
X461500D01*
G01Y390700D02*
X465500D01*
G01X469500Y90300D02*
Y92700D01*
G01X473500Y90300D02*
X469500D01*
G01X473500Y92700D02*
Y90300D01*
G01X469500Y92700D02*
X473500D01*
G01X469500Y95300D02*
Y97700D01*
G01X473500Y95300D02*
X469500D01*
G01X473500Y97700D02*
Y95300D01*
G01X469500Y97700D02*
X473500D01*
G01X463996Y128024D02*
Y130424D01*
G01X477866Y138836D02*
Y142836D01*
G01X475466Y138836D02*
X477866D01*
G01X475466Y142836D02*
Y138836D01*
G01X477866Y142836D02*
X475466D01*
G01X463933Y155584D02*
X467933D01*
G01X463933Y157984D02*
Y155584D01*
G01X467933Y157984D02*
X463933D01*
G01X467933Y155584D02*
Y157984D01*
G01X468000Y176700D02*
Y174300D01*
G01X464000Y176700D02*
X468000D01*
G01X464000Y174300D02*
Y176700D01*
G01X468000Y174300D02*
X464000D01*
G01X463996Y167395D02*
Y169795D01*
G01X467934Y179206D02*
Y181606D01*
G01X463934Y179206D02*
X467934D01*
G01X463934Y181606D02*
Y179206D01*
G01X467870Y167395D02*
X471870D01*
G01X467870Y169795D02*
Y167395D01*
G01X471870Y169795D02*
X467870D01*
G01X471870Y167395D02*
Y169795D01*
G01X476800Y186211D02*
X479200D01*
G01X476800Y182211D02*
Y186211D01*
G01X479200Y182211D02*
X476800D01*
G01X479200Y186211D02*
Y182211D01*
G01X463997Y194954D02*
Y197354D01*
G01Y191017D02*
Y193417D01*
G01X465165Y184312D02*
Y188312D01*
G01X467934Y181606D02*
X463934D01*
G01X466702Y188312D02*
Y184312D01*
G01X469102Y188312D02*
X466702D01*
G01X469102Y184312D02*
Y188312D01*
G01X466702Y184312D02*
X469102D01*
G01X466702Y211871D02*
X469102D01*
G01D02*
Y215871D01*
G01X466702D02*
Y211871D01*
G01X475808Y201291D02*
X471808D01*
G01X475808Y198891D02*
Y201291D01*
G01X471808Y198891D02*
X475808D01*
G01X471808Y201291D02*
Y198891D01*
G01X470639Y215871D02*
Y211871D01*
G01X473039D02*
Y215871D01*
G01X470639Y211871D02*
X473039D01*
G01X471871Y209165D02*
X467871D01*
G01X471871Y206765D02*
Y209165D01*
G01X467871Y206765D02*
X471871D01*
G01X467871Y209165D02*
Y206765D01*
G01X469102Y215871D02*
X466702D01*
G01X473039D02*
X470639D01*
G01X463200Y246000D02*
Y242000D01*
G01X477700Y356300D02*
Y353900D01*
G01X473700D02*
Y356300D01*
G01X477700Y353900D02*
X473700D01*
G01Y356300D02*
X477700D01*
G01X465500Y390700D02*
Y388300D01*
G01Y395200D02*
Y392800D01*
G01X492600Y123800D02*
Y128800D01*
G01X500600Y123800D02*
X492600D01*
G01Y128800D02*
X500600D01*
G01X492500Y164200D02*
Y161800D01*
G01X488500D02*
Y164200D01*
G01X492500Y161800D02*
X488500D01*
G01Y164200D02*
X492500D01*
G01X488500Y166300D02*
Y168700D01*
G01X492500Y166300D02*
X488500D01*
G01X492500Y168700D02*
Y166300D01*
G01X488500Y168700D02*
X492500D01*
G01X488500Y175300D02*
Y177700D01*
G01X492500Y175300D02*
X488500D01*
G01X492500Y177700D02*
Y175300D01*
G01X488500Y177700D02*
X492500D01*
G01Y182200D02*
Y179800D01*
G01X488500D02*
Y182200D01*
G01X492500Y179800D02*
X488500D01*
G01X492500Y198700D02*
Y196300D01*
G01X488500D02*
Y198700D01*
G01X492500Y196300D02*
X488500D01*
G01Y182200D02*
X492500D01*
G01Y186700D02*
Y184300D01*
G01X488500Y186700D02*
X492500D01*
G01X488500Y184300D02*
Y186700D01*
G01X492500Y184300D02*
X488500D01*
G01Y198700D02*
X492500D01*
G01X488500Y201300D02*
Y203700D01*
G01X492500Y201300D02*
X488500D01*
G01X492500Y203700D02*
Y201300D01*
G01X488500Y203700D02*
X492500D01*
G01X497300Y268700D02*
X494900D01*
G01X497300Y272700D02*
Y268700D01*
G01X494900Y272700D02*
X497300D01*
G01X494900Y268700D02*
Y272700D01*
G01X489700Y350500D02*
X487300D01*
G01X489700Y354500D02*
Y350500D01*
G01X487300Y354500D02*
X489700D01*
G01X487300Y350500D02*
Y354500D01*
G01X499700Y350500D02*
X497300D01*
G01Y354500D02*
X499700D01*
G01X497300Y350500D02*
Y354500D01*
G01X494700Y350500D02*
X492300D01*
G01X494700Y354500D02*
Y350500D01*
G01X492300Y354500D02*
X494700D01*
G01X492300Y350500D02*
Y354500D01*
G01X500600Y128800D02*
Y123800D01*
G01X508700Y242900D02*
X500700D01*
G01X508700Y247900D02*
Y242900D01*
G01X500700Y247900D02*
X508700D01*
G01X500700Y242900D02*
Y247900D01*
G01X499700Y354500D02*
Y350500D01*
G01X499000Y344300D02*
Y346700D01*
G01X503000Y344300D02*
X499000D01*
G01X503000Y346700D02*
Y344300D01*
G01X499000Y346700D02*
X503000D01*
G01X507300Y389500D02*
X509700D01*
G01X507300Y385500D02*
Y389500D01*
G01X509700Y385500D02*
X507300D01*
G01X509700Y389500D02*
Y385500D01*
G01X502300Y389500D02*
X504700D01*
G01X502300Y385500D02*
Y389500D01*
G01X504700Y385500D02*
X502300D01*
G01X504700Y389500D02*
Y385500D01*
G01X529000Y261200D02*
X526600D01*
G01X529000Y265200D02*
Y261200D01*
G01X526600Y265200D02*
X529000D01*
G01X526600Y261200D02*
Y265200D01*
G01X539376Y351645D02*
X523824D01*
G01D02*
Y369755D01*
G01D02*
X539376D01*
G01X528500Y416001D02*
X526100D01*
G01X528500Y420001D02*
Y416001D01*
G01X526100Y420001D02*
X528500D01*
G01X526100Y416001D02*
Y420001D01*
G01X531100D02*
X533500D01*
G01X531100Y416001D02*
Y420001D01*
G01X533500Y416001D02*
X531100D01*
G01X540500Y67800D02*
Y70200D01*
G01X544500Y67800D02*
X540500D01*
G01X544500Y70200D02*
Y67800D01*
G01X540500Y70200D02*
X544500D01*
G01Y65200D02*
Y62800D01*
G01X540500Y65200D02*
X544500D01*
G01X540500Y62800D02*
Y65200D01*
G01X544500Y62800D02*
X540500D01*
G01X537800Y160500D02*
Y164500D01*
G01X540200Y160500D02*
X537800D01*
G01X540200Y164500D02*
Y160500D01*
G01X537800Y164500D02*
X540200D01*
G01X542500Y186000D02*
Y178000D01*
G01X537500D02*
Y186000D01*
G01X542500Y178000D02*
X537500D01*
G01Y186000D02*
X542500D01*
G01X549800Y206500D02*
X552200D01*
G01X549800Y202500D02*
Y206500D01*
G01X552200Y202500D02*
X549800D01*
G01Y213000D02*
Y217000D01*
G01X552200Y213000D02*
X549800D01*
G01X539000Y226300D02*
Y228700D01*
G01X543000Y226300D02*
X539000D01*
G01X543000Y228700D02*
Y226300D01*
G01X539000Y228700D02*
X543000D01*
G01X549800Y232500D02*
Y236500D01*
G01X552200Y232500D02*
X549800D01*
G01X545300D02*
Y236500D01*
G01X547700Y232500D02*
X545300D01*
G01X547700Y236500D02*
Y232500D01*
G01X549800Y217000D02*
X552200D01*
G01X549800Y236500D02*
X552200D01*
G01X545300D02*
X547700D01*
G01X546450Y263850D02*
X544050D01*
G01X546450Y267850D02*
Y263850D01*
G01X544050Y267850D02*
X546450D01*
G01X544050Y263850D02*
Y267850D01*
G01X544000Y281200D02*
X546400D01*
G01X544000Y277200D02*
Y281200D01*
G01X546400Y277200D02*
X544000D01*
G01X546400Y281200D02*
Y277200D01*
G01X544000Y296350D02*
X546400D01*
G01X544000Y292350D02*
Y296350D01*
G01X546400Y292350D02*
X544000D01*
G01X546400Y296350D02*
Y292350D01*
G01X544000Y302000D02*
Y306000D01*
G01X546400Y302000D02*
X544000D01*
G01X546400Y306000D02*
Y302000D01*
G01X545500Y285800D02*
Y288200D01*
G01X549500Y285800D02*
X545500D01*
G01X549500Y288200D02*
Y285800D01*
G01X545500Y288200D02*
X549500D01*
G01X545400Y318100D02*
Y323100D01*
G01X553400Y318100D02*
X545400D01*
G01X544000Y306000D02*
X546400D01*
G01X545800Y333900D02*
Y338900D01*
G01X553800Y333900D02*
X545800D01*
G01Y331300D02*
X553800D01*
G01X545800Y326300D02*
Y331300D01*
G01X553800Y326300D02*
X545800D01*
G01X545400Y323100D02*
X553400D01*
G01X545800Y346600D02*
X553800D01*
G01X545800Y341600D02*
Y346600D01*
G01X553800Y341600D02*
X545800D01*
G01Y338900D02*
X553800D01*
G01X539376Y369755D02*
Y351645D01*
G01X538542Y345498D02*
Y340498D01*
G01X541042Y342998D02*
X536042D01*
G01X544700Y412500D02*
X542300D01*
G01X544700Y416500D02*
Y412500D01*
G01X542300Y416500D02*
X544700D01*
G01X542300Y412500D02*
Y416500D01*
G01Y422000D02*
Y426000D01*
G01X544700Y422000D02*
X542300D01*
G01X544700Y426000D02*
Y422000D01*
G01X533500Y420001D02*
Y416001D01*
G01X542300Y426000D02*
X544700D01*
G01X554500Y74600D02*
X556900D01*
G01X554500Y70600D02*
Y74600D01*
G01X556900Y70600D02*
X554500D01*
G01X556900Y74600D02*
Y70600D01*
G01X556700Y60900D02*
X554300D01*
G01X556700Y64900D02*
Y60900D01*
G01X554300Y64900D02*
X556700D01*
G01X554300Y60900D02*
Y64900D01*
G01X559000Y196800D02*
Y199200D01*
G01X563000Y196800D02*
X559000D01*
G01X563000Y199200D02*
Y196800D01*
G01X552200Y206500D02*
Y202500D01*
G01X559000Y199200D02*
X563000D01*
G01X552200Y217000D02*
Y213000D01*
G01X561200Y232500D02*
X558800D01*
G01X561200Y236500D02*
Y232500D01*
G01X558800D02*
Y236500D01*
G01X556700Y232500D02*
X554300D01*
G01X556700Y236500D02*
Y232500D01*
G01X554300D02*
Y236500D01*
G01X552200D02*
Y232500D01*
G01X563050Y216450D02*
X564950D01*
G01X563050Y217550D02*
Y216450D01*
G01X564950Y217550D02*
X563050D01*
G01X564950Y216450D02*
Y217550D01*
G01X563850Y233260D02*
Y235740D01*
G01X565150Y233260D02*
X563850D01*
G01X565150Y235740D02*
Y233260D01*
G01X563850Y235740D02*
X565150D01*
G01X558800Y236500D02*
X561200D01*
G01X554300D02*
X556700D01*
G01X566650Y265550D02*
Y263600D01*
G01X568450Y265550D02*
X566650D01*
G01Y263600D02*
X568450D01*
G01X565675Y270650D02*
Y265550D01*
G01D02*
X576925D01*
G01X550500Y265200D02*
X554500D01*
G01X550500Y262800D02*
Y265200D01*
G01X554500Y262800D02*
X550500D01*
G01X554500Y265200D02*
Y262800D01*
G01X550500Y260700D02*
X554500D01*
G01X550500Y258300D02*
Y260700D01*
G01X554500Y258300D02*
X550500D01*
G01X554500Y260700D02*
Y258300D01*
G01X566650Y272600D02*
Y270650D01*
G01X568450Y272600D02*
X566650D01*
G01Y270650D02*
X568450D01*
G01X576925D02*
X565675D01*
G01X550300Y273300D02*
X554300D01*
G01X550300Y270900D02*
Y273300D01*
G01X554300Y270900D02*
X550300D01*
G01X554300Y273300D02*
Y270900D01*
G01X550500Y278200D02*
X554500D01*
G01X550500Y275800D02*
Y278200D01*
G01X554500Y275800D02*
X550500D01*
G01X554500Y278200D02*
Y275800D01*
G01X550500Y282700D02*
X554500D01*
G01X550500Y280300D02*
Y282700D01*
G01X554500Y280300D02*
X550500D01*
G01X554500Y282700D02*
Y280300D01*
G01X565175Y294050D02*
X576425D01*
G01Y299150D02*
X565175D01*
G01D02*
Y294050D01*
G01X566150Y299150D02*
X567950D01*
G01Y301100D02*
X566150D01*
G01D02*
Y299150D01*
G01Y292100D02*
X567950D01*
G01Y294050D02*
X566150D01*
G01D02*
Y292100D01*
G01X550300Y293450D02*
X554300D01*
G01X550300Y291050D02*
Y293450D01*
G01X554300Y291050D02*
X550300D01*
G01X554300Y293450D02*
Y291050D01*
G01X550500Y300800D02*
Y303200D01*
G01X554500Y300800D02*
X550500D01*
G01X554500Y303200D02*
Y300800D01*
G01X553400Y323100D02*
Y318100D01*
G01X550500Y303200D02*
X554500D01*
G01X550500Y307700D02*
X554500D01*
G01X550500Y305300D02*
Y307700D01*
G01X554500Y305300D02*
X550500D01*
G01X554500Y307700D02*
Y305300D01*
G01X553800Y338900D02*
Y333900D01*
G01Y331300D02*
Y326300D01*
G01Y346600D02*
Y341600D01*
G01X557000Y408200D02*
Y405800D01*
G01X553000D02*
Y408200D01*
G01X557000Y405800D02*
X553000D01*
G01X565800Y422000D02*
Y426000D01*
G01X568200Y422000D02*
X565800D01*
G01X554300D02*
Y426000D01*
G01X556700Y422000D02*
X554300D01*
G01X556700Y426000D02*
Y422000D01*
G01X553000Y408200D02*
X557000D01*
G01X553000Y410300D02*
Y412700D01*
G01X557000Y410300D02*
X553000D01*
G01X557000Y412700D02*
Y410300D01*
G01X553000Y412700D02*
X557000D01*
G01X566300Y412500D02*
X568700D01*
G01X566300Y408500D02*
Y412500D01*
G01X568700Y408500D02*
X566300D01*
G01X565800Y426000D02*
X568200D01*
G01X554300D02*
X556700D01*
G01X583700Y75500D02*
X581300D01*
G01X583700Y79500D02*
Y75500D01*
G01X581300D02*
Y79500D01*
G01X576300Y75500D02*
Y79500D01*
G01X578700Y75500D02*
X576300D01*
G01X578700Y79500D02*
Y75500D01*
G01X576000Y69900D02*
X578400D01*
G01X576000Y65900D02*
Y69900D01*
G01X578400Y65900D02*
X576000D01*
G01X578400Y69900D02*
Y65900D01*
G01X581300Y79500D02*
X583700D01*
G01X576300D02*
X578700D01*
G01X576000Y196500D02*
X568000D01*
G01X576000Y201500D02*
Y196500D01*
G01X568000D02*
Y201500D01*
G01D02*
X576000D01*
G01X574200Y232500D02*
Y236500D01*
G01X576600Y232500D02*
X574200D01*
G01X576600Y236500D02*
Y232500D01*
G01X571800Y231300D02*
Y237700D01*
G01X568200Y231300D02*
X571800D01*
G01X568200Y237700D02*
Y231300D01*
G01X574200Y236500D02*
X576600D01*
G01X571800Y237700D02*
X568200D01*
G01X572550Y265550D02*
Y263600D01*
G01X575950Y265550D02*
X572550D01*
G01X575950Y263600D02*
Y265550D01*
G01X572550Y263600D02*
X575950D01*
G01X568450D02*
Y265550D01*
G01X576925D02*
Y270650D01*
G01X574150Y272600D02*
Y270650D01*
G01X575950Y272600D02*
X574150D01*
G01X575950Y270650D02*
Y272600D01*
G01X574150Y270650D02*
X575950D01*
G01X568450D02*
Y272600D01*
G01X567950Y299150D02*
Y301100D01*
G01Y292100D02*
Y294050D01*
G01X576425D02*
Y299150D01*
G01X573650D02*
X575450D01*
G01D02*
Y301100D01*
G01D02*
X573650D01*
G01D02*
Y299150D01*
G01X572050Y292100D02*
X575450D01*
G01D02*
Y294050D01*
G01D02*
X572050D01*
G01D02*
Y292100D01*
G01X572100Y389500D02*
Y391900D01*
G01X576100Y389500D02*
X572100D01*
G01X576100Y391900D02*
Y389500D01*
G01X572100Y384500D02*
Y386900D01*
G01X576100Y384500D02*
X572100D01*
G01X576100Y386900D02*
Y384500D01*
G01X572100Y386900D02*
X576100D01*
G01X572100Y391900D02*
X576100D01*
G01X581000Y408700D02*
Y406300D01*
G01X577000D02*
Y408700D01*
G01X581000Y406300D02*
X577000D01*
G01X577800Y422000D02*
Y426000D01*
G01X580200Y422000D02*
X577800D01*
G01X580200Y426000D02*
Y422000D01*
G01X568200Y426000D02*
Y422000D01*
G01X577000Y410800D02*
Y413200D01*
G01X581000Y410800D02*
X577000D01*
G01X581000Y413200D02*
Y410800D01*
G01X577000Y413200D02*
X581000D01*
G01X577000Y408700D02*
X581000D01*
G01X568700Y412500D02*
Y408500D01*
G01X577800Y426000D02*
X580200D01*
G01X596800Y146000D02*
X599200D01*
G01X596800Y142000D02*
Y146000D01*
G01X599200Y142000D02*
X596800D01*
G01X599200Y146000D02*
Y142000D01*
G01X596800Y158000D02*
X599200D01*
G01X596800Y154000D02*
Y158000D01*
G01X599200Y154000D02*
X596800D01*
G01X599200Y158000D02*
Y154000D01*
G01X596800Y163500D02*
Y167500D01*
G01X599200Y163500D02*
X596800D01*
G01X599200Y167500D02*
Y163500D01*
G01X596800Y167500D02*
X599200D01*
G01X596800Y178000D02*
X599200D01*
G01X596800Y174000D02*
Y178000D01*
G01X599200Y174000D02*
X596800D01*
G01X599200Y178000D02*
Y174000D01*
G01X593102Y190965D02*
X590702D01*
G01X593102Y194965D02*
Y190965D01*
G01X590702Y194965D02*
X593102D01*
G01X590702Y190965D02*
Y194965D01*
G01X595702D02*
X598102D01*
G01X595702Y190965D02*
Y194965D01*
G01X598102Y190965D02*
X595702D01*
G01X598102Y194965D02*
Y190965D01*
G01X600702Y194965D02*
X603102D01*
G01X600702Y190965D02*
Y194965D01*
G01X603102Y190965D02*
X600702D01*
G01X599500Y262700D02*
X603500D01*
G01X599500Y260300D02*
Y262700D01*
G01X603500Y260300D02*
X599500D01*
G01Y280200D02*
X603500D01*
G01X599500Y277800D02*
Y280200D01*
G01X603500Y277800D02*
X599500D01*
G01X601500Y422000D02*
Y426000D01*
G01X603900Y422000D02*
X601500D01*
G01X601300Y413000D02*
X603700D01*
G01X601300Y409000D02*
Y413000D01*
G01X603700Y409000D02*
X601300D01*
G01X589800Y413000D02*
X592200D01*
G01X589800Y409000D02*
Y413000D01*
G01X592200Y409000D02*
X589800D01*
G01X592200Y413000D02*
Y409000D01*
G01X601500Y426000D02*
X603900D01*
G01X618200Y143500D02*
X615800D01*
G01X618200Y147500D02*
Y143500D01*
G01X615800D02*
Y147500D01*
G01D02*
X618200D01*
G01Y153500D02*
X615800D01*
G01X618200Y157500D02*
Y153500D01*
G01X615800Y157500D02*
X618200D01*
G01X615800Y153500D02*
Y157500D01*
G01X618200Y163500D02*
X615800D01*
G01X618200Y167500D02*
Y163500D01*
G01X615800D02*
Y167500D01*
G01D02*
X618200D01*
G01X614300Y177000D02*
Y181000D01*
G01X616700Y177000D02*
X614300D01*
G01X616700Y181000D02*
Y177000D01*
G01X605702Y194965D02*
X608102D01*
G01X605702Y190965D02*
Y194965D01*
G01X608102Y190965D02*
X605702D01*
G01X608102Y194965D02*
Y190965D01*
G01X603102Y194965D02*
Y190965D01*
G01X619800Y196874D02*
Y200874D01*
G01X622200Y196874D02*
X619800D01*
G01X614300Y181000D02*
X616700D01*
G01X619800Y200874D02*
X622200D01*
G01X603500Y262700D02*
Y260300D01*
G01Y280200D02*
Y277800D01*
G01X612800Y422000D02*
Y426000D01*
G01X615200Y422000D02*
X612800D01*
G01X615200Y426000D02*
Y422000D01*
G01X603900Y426000D02*
Y422000D01*
G01X613300Y413500D02*
X615700D01*
G01X613300Y409500D02*
Y413500D01*
G01X615700Y409500D02*
X613300D01*
G01X615700Y413500D02*
Y409500D01*
G01X603700Y413000D02*
Y409000D01*
G01X612800Y426000D02*
X615200D01*
G01X651839Y65354D02*
G02I-11800J0D01*
G01X622200Y200874D02*
Y196874D01*
G01X626700D02*
X624300D01*
G01X626700Y200874D02*
Y196874D01*
G01X624300D02*
Y200874D01*
G01X628800Y196874D02*
Y200874D01*
G01X631200Y196874D02*
X628800D01*
G01X631200Y200874D02*
Y196874D01*
G01X624300Y200874D02*
X626700D01*
G01X628800D02*
X631200D01*
G01X651839Y417835D02*
G02I-11800J0D01*
G01X638000Y95300D02*
Y97700D01*
G01X642000Y95300D02*
X638000D01*
G01X642000Y97700D02*
Y95300D01*
G01X638000Y97700D02*
X642000D01*
G01X638000Y100800D02*
Y103200D01*
G01X642000Y100800D02*
X638000D01*
G01X642000Y103200D02*
Y100800D01*
G01X638000Y103200D02*
X642000D01*
G01X638000Y106800D02*
Y109200D01*
G01X642000Y106800D02*
X638000D01*
G01X642000Y109200D02*
Y106800D01*
G01X638000Y109200D02*
X642000D01*
G01X27452Y279583D02*
X30552D01*
Y280542D01*
X30397Y280848D01*
X30190Y281040D01*
X29777Y281117D01*
X29364Y281040D01*
X29105Y280810D01*
X28950Y280542D01*
Y279583D01*
G01Y280542D02*
X27452Y281117D01*
G01X28072Y282607D02*
X27710Y282837D01*
X27504Y283143D01*
X27452Y283488D01*
X27504Y283795D01*
X27762Y284102D01*
X28072Y284293D01*
X28382Y284332D01*
X28744Y284255D01*
X29002Y283987D01*
X29105Y283718D01*
Y283373D01*
G01Y283718D02*
X29260Y283948D01*
X29519Y284140D01*
X29829Y284217D01*
X30139Y284140D01*
X30397Y283948D01*
X30552Y283603D01*
X30500Y283258D01*
X30294Y282913D01*
G01X28072Y285707D02*
X27710Y285937D01*
X27504Y286243D01*
X27452Y286588D01*
X27504Y286895D01*
X27762Y287202D01*
X28072Y287393D01*
X28382Y287432D01*
X28744Y287355D01*
X29002Y287087D01*
X29105Y286818D01*
Y286473D01*
G01Y286818D02*
X29260Y287048D01*
X29519Y287240D01*
X29829Y287317D01*
X30139Y287240D01*
X30397Y287048D01*
X30552Y286703D01*
X30500Y286358D01*
X30294Y286013D01*
G01X27452Y290110D02*
X30552D01*
X28330Y288692D01*
Y290608D01*
G01X25417Y286482D02*
Y289582D01*
X24458D01*
X24152Y289427D01*
X23960Y289220D01*
X23883Y288807D01*
X23960Y288394D01*
X24190Y288135D01*
X24458Y287980D01*
X25417D01*
G01X24458D02*
X23883Y286482D01*
G01X22393Y287102D02*
X22163Y286740D01*
X21857Y286534D01*
X21512Y286482D01*
X21205Y286534D01*
X20898Y286792D01*
X20707Y287102D01*
X20668Y287412D01*
X20745Y287774D01*
X21013Y288032D01*
X21282Y288135D01*
X21627D01*
G01X21282D02*
X21052Y288290D01*
X20860Y288549D01*
X20783Y288859D01*
X20860Y289169D01*
X21052Y289427D01*
X21397Y289582D01*
X21742Y289530D01*
X22087Y289324D01*
G01X19293Y287102D02*
X19063Y286740D01*
X18757Y286534D01*
X18412Y286482D01*
X18105Y286534D01*
X17798Y286792D01*
X17607Y287102D01*
X17568Y287412D01*
X17645Y287774D01*
X17913Y288032D01*
X18182Y288135D01*
X18527D01*
G01X18182D02*
X17952Y288290D01*
X17760Y288549D01*
X17683Y288859D01*
X17760Y289169D01*
X17952Y289427D01*
X18297Y289582D01*
X18642Y289530D01*
X18987Y289324D01*
G01X16078Y287774D02*
X15810Y288135D01*
X15580Y288342D01*
X15273Y288445D01*
X15005Y288342D01*
X14813Y288135D01*
X14660Y287825D01*
X14622Y287464D01*
X14660Y287154D01*
X14813Y286844D01*
X15043Y286585D01*
X15312Y286482D01*
X15618Y286585D01*
X15887Y286895D01*
X16040Y287360D01*
X16078Y287877D01*
X16002Y288549D01*
X15887Y288910D01*
X15695Y289272D01*
X15427Y289530D01*
X15158Y289582D01*
X14890Y289479D01*
X14698Y289220D01*
G01X25417Y296482D02*
Y299582D01*
X24458D01*
X24152Y299427D01*
X23960Y299220D01*
X23883Y298807D01*
X23960Y298394D01*
X24190Y298135D01*
X24458Y297980D01*
X25417D01*
G01X24458D02*
X23883Y296482D01*
G01X22393Y297102D02*
X22163Y296740D01*
X21857Y296534D01*
X21512Y296482D01*
X21205Y296534D01*
X20898Y296792D01*
X20707Y297102D01*
X20668Y297412D01*
X20745Y297774D01*
X21013Y298032D01*
X21282Y298135D01*
X21627D01*
G01X21282D02*
X21052Y298290D01*
X20860Y298549D01*
X20783Y298859D01*
X20860Y299169D01*
X21052Y299427D01*
X21397Y299582D01*
X21742Y299530D01*
X22087Y299324D01*
G01X19293Y297102D02*
X19063Y296740D01*
X18757Y296534D01*
X18412Y296482D01*
X18105Y296534D01*
X17798Y296792D01*
X17607Y297102D01*
X17568Y297412D01*
X17645Y297774D01*
X17913Y298032D01*
X18182Y298135D01*
X18527D01*
G01X18182D02*
X17952Y298290D01*
X17760Y298549D01*
X17683Y298859D01*
X17760Y299169D01*
X17952Y299427D01*
X18297Y299582D01*
X18642Y299530D01*
X18987Y299324D01*
G01X15427Y296482D02*
X15350Y297154D01*
X15235Y297722D01*
X15082Y298239D01*
X14890Y298807D01*
X14583Y299582D01*
X16117D01*
G01X25417Y301832D02*
Y304932D01*
X24458D01*
X24152Y304777D01*
X23960Y304570D01*
X23883Y304157D01*
X23960Y303744D01*
X24190Y303485D01*
X24458Y303330D01*
X25417D01*
G01X24458D02*
X23883Y301832D01*
G01X22393Y302452D02*
X22163Y302090D01*
X21857Y301884D01*
X21512Y301832D01*
X21205Y301884D01*
X20898Y302142D01*
X20707Y302452D01*
X20668Y302762D01*
X20745Y303124D01*
X21013Y303382D01*
X21282Y303485D01*
X21627D01*
G01X21282D02*
X21052Y303640D01*
X20860Y303899D01*
X20783Y304209D01*
X20860Y304519D01*
X21052Y304777D01*
X21397Y304932D01*
X21742Y304880D01*
X22087Y304674D01*
G01X19293Y302452D02*
X19063Y302090D01*
X18757Y301884D01*
X18412Y301832D01*
X18105Y301884D01*
X17798Y302142D01*
X17607Y302452D01*
X17568Y302762D01*
X17645Y303124D01*
X17913Y303382D01*
X18182Y303485D01*
X18527D01*
G01X18182D02*
X17952Y303640D01*
X17760Y303899D01*
X17683Y304209D01*
X17760Y304519D01*
X17952Y304777D01*
X18297Y304932D01*
X18642Y304880D01*
X18987Y304674D01*
G01X15350Y301832D02*
X15082Y301884D01*
X14775Y302039D01*
X14583Y302297D01*
X14507Y302659D01*
X14583Y303020D01*
X14813Y303330D01*
X15158Y303485D01*
X15542D01*
X15772Y303589D01*
X15963Y303847D01*
X16040Y304209D01*
X15925Y304570D01*
X15657Y304829D01*
X15350Y304932D01*
X15043Y304829D01*
X14775Y304570D01*
X14660Y304209D01*
X14737Y303847D01*
X14928Y303589D01*
X15158Y303485D01*
X15542D01*
X15887Y303330D01*
X16117Y303020D01*
X16193Y302659D01*
X16117Y302297D01*
X15925Y302039D01*
X15618Y301884D01*
X15350Y301832D01*
G01X25417Y291482D02*
Y294582D01*
X24458D01*
X24152Y294427D01*
X23960Y294220D01*
X23883Y293807D01*
X23960Y293394D01*
X24190Y293135D01*
X24458Y292980D01*
X25417D01*
G01X24458D02*
X23883Y291482D01*
G01X22393Y292102D02*
X22163Y291740D01*
X21857Y291534D01*
X21512Y291482D01*
X21205Y291534D01*
X20898Y291792D01*
X20707Y292102D01*
X20668Y292412D01*
X20745Y292774D01*
X21013Y293032D01*
X21282Y293135D01*
X21627D01*
G01X21282D02*
X21052Y293290D01*
X20860Y293549D01*
X20783Y293859D01*
X20860Y294169D01*
X21052Y294427D01*
X21397Y294582D01*
X21742Y294530D01*
X22087Y294324D01*
G01X19293Y292102D02*
X19063Y291740D01*
X18757Y291534D01*
X18412Y291482D01*
X18105Y291534D01*
X17798Y291792D01*
X17607Y292102D01*
X17568Y292412D01*
X17645Y292774D01*
X17913Y293032D01*
X18182Y293135D01*
X18527D01*
G01X18182D02*
X17952Y293290D01*
X17760Y293549D01*
X17683Y293859D01*
X17760Y294169D01*
X17952Y294427D01*
X18297Y294582D01*
X18642Y294530D01*
X18987Y294324D01*
G01X16193Y291947D02*
X15963Y291689D01*
X15695Y291534D01*
X15350Y291482D01*
X15005Y291585D01*
X14737Y291792D01*
X14545Y292154D01*
X14507Y292567D01*
X14583Y292980D01*
X14775Y293239D01*
X15043Y293445D01*
X15312Y293497D01*
X15580Y293445D01*
X15925Y293239D01*
X15810Y294582D01*
X14775D01*
G01X24257Y309824D02*
X24487Y309979D01*
X24755Y310082D01*
X25062D01*
X25407Y309927D01*
X25675Y309669D01*
X25867Y309359D01*
X26020Y308842D01*
X26058Y308377D01*
X25982Y307912D01*
X25867Y307602D01*
X25637Y307292D01*
X25368Y307085D01*
X25100Y306982D01*
X24832D01*
X24563Y307085D01*
X24333Y307240D01*
X24142Y307447D01*
G01X22843Y307602D02*
X22613Y307240D01*
X22307Y307034D01*
X21962Y306982D01*
X21655Y307034D01*
X21348Y307292D01*
X21157Y307602D01*
X21118Y307912D01*
X21195Y308274D01*
X21463Y308532D01*
X21732Y308635D01*
X22077D01*
G01X21732D02*
X21502Y308790D01*
X21310Y309049D01*
X21233Y309359D01*
X21310Y309669D01*
X21502Y309927D01*
X21847Y310082D01*
X22192Y310030D01*
X22537Y309824D01*
G01X19552Y307344D02*
X19283Y307085D01*
X18977Y306982D01*
X18670Y307085D01*
X18402Y307395D01*
X18210Y307860D01*
X18133Y308325D01*
Y308894D01*
X18210Y309359D01*
X18402Y309772D01*
X18632Y309979D01*
X18900Y310082D01*
X19207Y309979D01*
X19437Y309772D01*
X19590Y309462D01*
X19667Y309049D01*
X19590Y308687D01*
X19398Y308325D01*
X19168Y308119D01*
X18900Y308067D01*
X18593Y308170D01*
X18363Y308429D01*
X18133Y308894D01*
G01X31950Y279583D02*
X35050D01*
Y280542D01*
X34895Y280848D01*
X34688Y281040D01*
X34275Y281117D01*
X33862Y281040D01*
X33603Y280810D01*
X33448Y280542D01*
Y279583D01*
G01Y280542D02*
X31950Y281117D01*
G01X32570Y282607D02*
X32208Y282837D01*
X32002Y283143D01*
X31950Y283488D01*
X32002Y283795D01*
X32260Y284102D01*
X32570Y284293D01*
X32880Y284332D01*
X33242Y284255D01*
X33500Y283987D01*
X33603Y283718D01*
Y283373D01*
G01Y283718D02*
X33758Y283948D01*
X34017Y284140D01*
X34327Y284217D01*
X34637Y284140D01*
X34895Y283948D01*
X35050Y283603D01*
X34998Y283258D01*
X34792Y282913D01*
G01X32570Y285707D02*
X32208Y285937D01*
X32002Y286243D01*
X31950Y286588D01*
X32002Y286895D01*
X32260Y287202D01*
X32570Y287393D01*
X32880Y287432D01*
X33242Y287355D01*
X33500Y287087D01*
X33603Y286818D01*
Y286473D01*
G01Y286818D02*
X33758Y287048D01*
X34017Y287240D01*
X34327Y287317D01*
X34637Y287240D01*
X34895Y287048D01*
X35050Y286703D01*
X34998Y286358D01*
X34792Y286013D01*
G01X32570Y288807D02*
X32208Y289037D01*
X32002Y289343D01*
X31950Y289688D01*
X32002Y289995D01*
X32260Y290302D01*
X32570Y290493D01*
X32880Y290532D01*
X33242Y290455D01*
X33500Y290187D01*
X33603Y289918D01*
Y289573D01*
G01Y289918D02*
X33758Y290148D01*
X34017Y290340D01*
X34327Y290417D01*
X34637Y290340D01*
X34895Y290148D01*
X35050Y289803D01*
X34998Y289458D01*
X34792Y289113D01*
G01X48393Y301582D02*
Y299360D01*
X48240Y298895D01*
X47933Y298585D01*
X47550Y298482D01*
X47167Y298585D01*
X46860Y298895D01*
X46707Y299360D01*
Y301582D01*
G01X44450Y298482D02*
X44182Y298534D01*
X43875Y298689D01*
X43683Y298947D01*
X43607Y299309D01*
X43683Y299670D01*
X43913Y299980D01*
X44258Y300135D01*
X44642D01*
X44872Y300239D01*
X45063Y300497D01*
X45140Y300859D01*
X45025Y301220D01*
X44757Y301479D01*
X44450Y301582D01*
X44143Y301479D01*
X43875Y301220D01*
X43760Y300859D01*
X43837Y300497D01*
X44028Y300239D01*
X44258Y300135D01*
X44642D01*
X44987Y299980D01*
X45217Y299670D01*
X45293Y299309D01*
X45217Y298947D01*
X45025Y298689D01*
X44718Y298534D01*
X44450Y298482D01*
G01X38643Y293197D02*
X38413Y292939D01*
X38145Y292784D01*
X37800Y292732D01*
X37455Y292835D01*
X37187Y293042D01*
X36995Y293404D01*
X36957Y293817D01*
X37033Y294230D01*
X37225Y294489D01*
X37493Y294695D01*
X37762Y294747D01*
X38030Y294695D01*
X38375Y294489D01*
X38260Y295832D01*
X37225D01*
G01X36800Y303232D02*
X36532Y303284D01*
X36225Y303439D01*
X36033Y303697D01*
X35957Y304059D01*
X36033Y304420D01*
X36263Y304730D01*
X36608Y304885D01*
X36992D01*
X37222Y304989D01*
X37413Y305247D01*
X37490Y305609D01*
X37375Y305970D01*
X37107Y306229D01*
X36800Y306332D01*
X36493Y306229D01*
X36225Y305970D01*
X36110Y305609D01*
X36187Y305247D01*
X36378Y304989D01*
X36608Y304885D01*
X36992D01*
X37337Y304730D01*
X37567Y304420D01*
X37643Y304059D01*
X37567Y303697D01*
X37375Y303439D01*
X37068Y303284D01*
X36800Y303232D01*
G01X67857Y62792D02*
X68087Y62947D01*
X68355Y63050D01*
X68662D01*
X69007Y62895D01*
X69275Y62637D01*
X69467Y62327D01*
X69620Y61810D01*
X69658Y61345D01*
X69582Y60880D01*
X69467Y60570D01*
X69237Y60260D01*
X68968Y60053D01*
X68700Y59950D01*
X68432D01*
X68163Y60053D01*
X67933Y60208D01*
X67742Y60415D01*
G01X65600Y59950D02*
X65332Y60002D01*
X65025Y60157D01*
X64833Y60415D01*
X64757Y60777D01*
X64833Y61138D01*
X65063Y61448D01*
X65408Y61603D01*
X65792D01*
X66022Y61707D01*
X66213Y61965D01*
X66290Y62327D01*
X66175Y62688D01*
X65907Y62947D01*
X65600Y63050D01*
X65293Y62947D01*
X65025Y62688D01*
X64910Y62327D01*
X64987Y61965D01*
X65178Y61707D01*
X65408Y61603D01*
X65792D01*
X66137Y61448D01*
X66367Y61138D01*
X66443Y60777D01*
X66367Y60415D01*
X66175Y60157D01*
X65868Y60002D01*
X65600Y59950D01*
G01X63228Y62533D02*
X62998Y62843D01*
X62730Y62998D01*
X62423Y63050D01*
X62040Y62947D01*
X61772Y62688D01*
X61695Y62378D01*
X61733Y62068D01*
X61887Y61810D01*
X62653Y61293D01*
X62998Y60932D01*
X63228Y60415D01*
X63305Y59950D01*
X61695D01*
G01X57182Y62183D02*
X60282D01*
Y63142D01*
X60127Y63448D01*
X59920Y63640D01*
X59507Y63717D01*
X59094Y63640D01*
X58835Y63410D01*
X58680Y63142D01*
Y62183D01*
G01Y63142D02*
X57182Y63717D01*
G01X57802Y65207D02*
X57440Y65437D01*
X57234Y65743D01*
X57182Y66088D01*
X57234Y66395D01*
X57492Y66702D01*
X57802Y66893D01*
X58112Y66932D01*
X58474Y66855D01*
X58732Y66587D01*
X58835Y66318D01*
Y65973D01*
G01Y66318D02*
X58990Y66548D01*
X59249Y66740D01*
X59559Y66817D01*
X59869Y66740D01*
X60127Y66548D01*
X60282Y66203D01*
X60230Y65858D01*
X60024Y65513D01*
G01X57182Y69073D02*
X57854Y69150D01*
X58422Y69265D01*
X58939Y69418D01*
X59507Y69610D01*
X60282Y69917D01*
Y68383D01*
G01X57544Y71598D02*
X57285Y71867D01*
X57182Y72173D01*
X57285Y72480D01*
X57595Y72748D01*
X58060Y72940D01*
X58525Y73017D01*
X59094D01*
X59559Y72940D01*
X59972Y72748D01*
X60179Y72518D01*
X60282Y72250D01*
X60179Y71943D01*
X59972Y71713D01*
X59662Y71560D01*
X59249Y71483D01*
X58887Y71560D01*
X58525Y71752D01*
X58319Y71982D01*
X58267Y72250D01*
X58370Y72557D01*
X58629Y72787D01*
X59094Y73017D01*
G01X51966Y62183D02*
X55066D01*
Y63142D01*
X54911Y63448D01*
X54704Y63640D01*
X54291Y63717D01*
X53878Y63640D01*
X53619Y63410D01*
X53464Y63142D01*
Y62183D01*
G01Y63142D02*
X51966Y63717D01*
G01Y66050D02*
X55066D01*
X54446Y65590D01*
G01X51966D02*
Y66510D01*
G01X54549Y68422D02*
X54859Y68652D01*
X55014Y68920D01*
X55066Y69227D01*
X54963Y69610D01*
X54704Y69878D01*
X54394Y69955D01*
X54084Y69917D01*
X53826Y69763D01*
X53309Y68997D01*
X52948Y68652D01*
X52431Y68422D01*
X51966Y68345D01*
Y69955D01*
G01X52586Y71407D02*
X52224Y71637D01*
X52018Y71943D01*
X51966Y72288D01*
X52018Y72595D01*
X52276Y72902D01*
X52586Y73093D01*
X52896Y73132D01*
X53258Y73055D01*
X53516Y72787D01*
X53619Y72518D01*
Y72173D01*
G01Y72518D02*
X53774Y72748D01*
X54033Y72940D01*
X54343Y73017D01*
X54653Y72940D01*
X54911Y72748D01*
X55066Y72403D01*
X55014Y72058D01*
X54808Y71713D01*
G01X52466Y85083D02*
X55566D01*
Y86042D01*
X55411Y86348D01*
X55204Y86540D01*
X54791Y86617D01*
X54378Y86540D01*
X54119Y86310D01*
X53964Y86042D01*
Y85083D01*
G01Y86042D02*
X52466Y86617D01*
G01Y89410D02*
X55566D01*
X53344Y87992D01*
Y89908D01*
G01X52828Y91398D02*
X52569Y91667D01*
X52466Y91973D01*
X52569Y92280D01*
X52879Y92548D01*
X53344Y92740D01*
X53809Y92817D01*
X54378D01*
X54843Y92740D01*
X55256Y92548D01*
X55463Y92318D01*
X55566Y92050D01*
X55463Y91743D01*
X55256Y91513D01*
X54946Y91360D01*
X54533Y91283D01*
X54171Y91360D01*
X53809Y91552D01*
X53603Y91782D01*
X53551Y92050D01*
X53654Y92357D01*
X53913Y92587D01*
X54378Y92817D01*
G01X53086Y94307D02*
X52724Y94537D01*
X52518Y94843D01*
X52466Y95188D01*
X52518Y95495D01*
X52776Y95802D01*
X53086Y95993D01*
X53396Y96032D01*
X53758Y95955D01*
X54016Y95687D01*
X54119Y95418D01*
Y95073D01*
G01Y95418D02*
X54274Y95648D01*
X54533Y95840D01*
X54843Y95917D01*
X55153Y95840D01*
X55411Y95648D01*
X55566Y95303D01*
X55514Y94958D01*
X55308Y94613D01*
G01X51966Y141083D02*
X55066D01*
Y142042D01*
X54911Y142348D01*
X54704Y142540D01*
X54291Y142617D01*
X53878Y142540D01*
X53619Y142310D01*
X53464Y142042D01*
Y141083D01*
G01Y142042D02*
X51966Y142617D01*
G01Y145410D02*
X55066D01*
X52844Y143992D01*
Y145908D01*
G01X52328Y147398D02*
X52069Y147667D01*
X51966Y147973D01*
X52069Y148280D01*
X52379Y148548D01*
X52844Y148740D01*
X53309Y148817D01*
X53878D01*
X54343Y148740D01*
X54756Y148548D01*
X54963Y148318D01*
X55066Y148050D01*
X54963Y147743D01*
X54756Y147513D01*
X54446Y147360D01*
X54033Y147283D01*
X53671Y147360D01*
X53309Y147552D01*
X53103Y147782D01*
X53051Y148050D01*
X53154Y148357D01*
X53413Y148587D01*
X53878Y148817D01*
G01X54549Y150422D02*
X54859Y150652D01*
X55014Y150920D01*
X55066Y151227D01*
X54963Y151610D01*
X54704Y151878D01*
X54394Y151955D01*
X54084Y151917D01*
X53826Y151763D01*
X53309Y150997D01*
X52948Y150652D01*
X52431Y150422D01*
X51966Y150345D01*
Y151955D01*
G01Y201583D02*
X55066D01*
Y202542D01*
X54911Y202848D01*
X54704Y203040D01*
X54291Y203117D01*
X53878Y203040D01*
X53619Y202810D01*
X53464Y202542D01*
Y201583D01*
G01Y202542D02*
X51966Y203117D01*
G01Y205910D02*
X55066D01*
X52844Y204492D01*
Y206408D01*
G01X52328Y207898D02*
X52069Y208167D01*
X51966Y208473D01*
X52069Y208780D01*
X52379Y209048D01*
X52844Y209240D01*
X53309Y209317D01*
X53878D01*
X54343Y209240D01*
X54756Y209048D01*
X54963Y208818D01*
X55066Y208550D01*
X54963Y208243D01*
X54756Y208013D01*
X54446Y207860D01*
X54033Y207783D01*
X53671Y207860D01*
X53309Y208052D01*
X53103Y208282D01*
X53051Y208550D01*
X53154Y208857D01*
X53413Y209087D01*
X53878Y209317D01*
G01X52431Y210807D02*
X52173Y211037D01*
X52018Y211305D01*
X51966Y211650D01*
X52069Y211995D01*
X52276Y212263D01*
X52638Y212455D01*
X53051Y212493D01*
X53464Y212417D01*
X53723Y212225D01*
X53929Y211957D01*
X53981Y211688D01*
X53929Y211420D01*
X53723Y211075D01*
X55066Y211190D01*
Y212225D01*
G01X51966Y255083D02*
X55066D01*
Y256042D01*
X54911Y256348D01*
X54704Y256540D01*
X54291Y256617D01*
X53878Y256540D01*
X53619Y256310D01*
X53464Y256042D01*
Y255083D01*
G01Y256042D02*
X51966Y256617D01*
G01Y259410D02*
X55066D01*
X52844Y257992D01*
Y259908D01*
G01X52328Y261398D02*
X52069Y261667D01*
X51966Y261973D01*
X52069Y262280D01*
X52379Y262548D01*
X52844Y262740D01*
X53309Y262817D01*
X53878D01*
X54343Y262740D01*
X54756Y262548D01*
X54963Y262318D01*
X55066Y262050D01*
X54963Y261743D01*
X54756Y261513D01*
X54446Y261360D01*
X54033Y261283D01*
X53671Y261360D01*
X53309Y261552D01*
X53103Y261782D01*
X53051Y262050D01*
X53154Y262357D01*
X53413Y262587D01*
X53878Y262817D01*
G01X51966Y265610D02*
X55066D01*
X52844Y264192D01*
Y266108D01*
G01X53840Y293232D02*
Y296332D01*
X55258Y294110D01*
X53342D01*
G01X84817Y64950D02*
Y68050D01*
X83858D01*
X83552Y67895D01*
X83360Y67688D01*
X83283Y67275D01*
X83360Y66862D01*
X83590Y66603D01*
X83858Y66448D01*
X84817D01*
G01X83858D02*
X83283Y64950D01*
G01X81793Y65570D02*
X81563Y65208D01*
X81257Y65002D01*
X80912Y64950D01*
X80605Y65002D01*
X80298Y65260D01*
X80107Y65570D01*
X80068Y65880D01*
X80145Y66242D01*
X80413Y66500D01*
X80682Y66603D01*
X81027D01*
G01X80682D02*
X80452Y66758D01*
X80260Y67017D01*
X80183Y67327D01*
X80260Y67637D01*
X80452Y67895D01*
X80797Y68050D01*
X81142Y67998D01*
X81487Y67792D01*
G01X77950Y71683D02*
X81050D01*
Y72642D01*
X80895Y72948D01*
X80688Y73140D01*
X80275Y73217D01*
X79862Y73140D01*
X79603Y72910D01*
X79448Y72642D01*
Y71683D01*
G01Y72642D02*
X77950Y73217D01*
G01X80533Y74822D02*
X80843Y75052D01*
X80998Y75320D01*
X81050Y75627D01*
X80947Y76010D01*
X80688Y76278D01*
X80378Y76355D01*
X80068Y76317D01*
X79810Y76163D01*
X79293Y75397D01*
X78932Y75052D01*
X78415Y74822D01*
X77950Y74745D01*
Y76355D01*
G01X70450Y78133D02*
X73550D01*
Y79092D01*
X73395Y79398D01*
X73188Y79590D01*
X72775Y79667D01*
X72362Y79590D01*
X72103Y79360D01*
X71948Y79092D01*
Y78133D01*
G01Y79092D02*
X70450Y79667D01*
G01Y82460D02*
X73550D01*
X71328Y81042D01*
Y82958D01*
G01X70915Y84257D02*
X70657Y84487D01*
X70502Y84755D01*
X70450Y85100D01*
X70553Y85445D01*
X70760Y85713D01*
X71122Y85905D01*
X71535Y85943D01*
X71948Y85867D01*
X72207Y85675D01*
X72413Y85407D01*
X72465Y85138D01*
X72413Y84870D01*
X72207Y84525D01*
X73550Y84640D01*
Y85675D01*
G01X73782Y87783D02*
X76882D01*
Y88742D01*
X76727Y89048D01*
X76520Y89240D01*
X76107Y89317D01*
X75694Y89240D01*
X75435Y89010D01*
X75280Y88742D01*
Y87783D01*
G01Y88742D02*
X73782Y89317D01*
G01Y91650D02*
X76882D01*
X76262Y91190D01*
G01X73782D02*
Y92110D01*
G01X75074Y94022D02*
X75435Y94290D01*
X75642Y94520D01*
X75745Y94827D01*
X75642Y95095D01*
X75435Y95287D01*
X75125Y95440D01*
X74764Y95478D01*
X74454Y95440D01*
X74144Y95287D01*
X73885Y95057D01*
X73782Y94788D01*
X73885Y94482D01*
X74195Y94213D01*
X74660Y94060D01*
X75177Y94022D01*
X75849Y94098D01*
X76210Y94213D01*
X76572Y94405D01*
X76830Y94673D01*
X76882Y94942D01*
X76779Y95210D01*
X76520Y95402D01*
G01X76365Y97122D02*
X76675Y97352D01*
X76830Y97620D01*
X76882Y97927D01*
X76779Y98310D01*
X76520Y98578D01*
X76210Y98655D01*
X75900Y98617D01*
X75642Y98463D01*
X75125Y97697D01*
X74764Y97352D01*
X74247Y97122D01*
X73782Y97045D01*
Y98655D01*
G01X77950Y87583D02*
X81050D01*
Y88542D01*
X80895Y88848D01*
X80688Y89040D01*
X80275Y89117D01*
X79862Y89040D01*
X79603Y88810D01*
X79448Y88542D01*
Y87583D01*
G01Y88542D02*
X77950Y89117D01*
G01Y91450D02*
X81050D01*
X80430Y90990D01*
G01X77950D02*
Y91910D01*
G01X79242Y93822D02*
X79603Y94090D01*
X79810Y94320D01*
X79913Y94627D01*
X79810Y94895D01*
X79603Y95087D01*
X79293Y95240D01*
X78932Y95278D01*
X78622Y95240D01*
X78312Y95087D01*
X78053Y94857D01*
X77950Y94588D01*
X78053Y94282D01*
X78363Y94013D01*
X78828Y93860D01*
X79345Y93822D01*
X80017Y93898D01*
X80378Y94013D01*
X80740Y94205D01*
X80998Y94473D01*
X81050Y94742D01*
X80947Y95010D01*
X80688Y95202D01*
G01X81050Y97650D02*
X80947Y97343D01*
X80688Y97113D01*
X80378Y96960D01*
X79965Y96845D01*
X79500Y96807D01*
X79035Y96845D01*
X78622Y96960D01*
X78312Y97113D01*
X78053Y97343D01*
X77950Y97650D01*
X78053Y97957D01*
X78312Y98187D01*
X78622Y98340D01*
X79035Y98455D01*
X79500Y98493D01*
X79965Y98455D01*
X80378Y98340D01*
X80688Y98187D01*
X80947Y97957D01*
X81050Y97650D01*
G01X68766Y87783D02*
X71866D01*
Y88742D01*
X71711Y89048D01*
X71504Y89240D01*
X71091Y89317D01*
X70678Y89240D01*
X70419Y89010D01*
X70264Y88742D01*
Y87783D01*
G01Y88742D02*
X68766Y89317D01*
G01Y91650D02*
X71866D01*
X71246Y91190D01*
G01X68766D02*
Y92110D01*
G01X70058Y94022D02*
X70419Y94290D01*
X70626Y94520D01*
X70729Y94827D01*
X70626Y95095D01*
X70419Y95287D01*
X70109Y95440D01*
X69748Y95478D01*
X69438Y95440D01*
X69128Y95287D01*
X68869Y95057D01*
X68766Y94788D01*
X68869Y94482D01*
X69179Y94213D01*
X69644Y94060D01*
X70161Y94022D01*
X70833Y94098D01*
X71194Y94213D01*
X71556Y94405D01*
X71814Y94673D01*
X71866Y94942D01*
X71763Y95210D01*
X71504Y95402D01*
G01X69386Y97007D02*
X69024Y97237D01*
X68818Y97543D01*
X68766Y97888D01*
X68818Y98195D01*
X69076Y98502D01*
X69386Y98693D01*
X69696Y98732D01*
X70058Y98655D01*
X70316Y98387D01*
X70419Y98118D01*
Y97773D01*
G01Y98118D02*
X70574Y98348D01*
X70833Y98540D01*
X71143Y98617D01*
X71453Y98540D01*
X71711Y98348D01*
X71866Y98003D01*
X71814Y97658D01*
X71608Y97313D01*
G01X75017Y152850D02*
Y155950D01*
X74058D01*
X73752Y155795D01*
X73560Y155588D01*
X73483Y155175D01*
X73560Y154762D01*
X73790Y154503D01*
X74058Y154348D01*
X75017D01*
G01X74058D02*
X73483Y152850D01*
G01X71150D02*
Y155950D01*
X71610Y155330D01*
G01Y152850D02*
X70690D01*
G01X67590D02*
Y155950D01*
X69008Y153728D01*
X67092D01*
G01X65793Y153315D02*
X65563Y153057D01*
X65295Y152902D01*
X64950Y152850D01*
X64605Y152953D01*
X64337Y153160D01*
X64145Y153522D01*
X64107Y153935D01*
X64183Y154348D01*
X64375Y154607D01*
X64643Y154813D01*
X64912Y154865D01*
X65180Y154813D01*
X65525Y154607D01*
X65410Y155950D01*
X64375D01*
G01X88317Y162350D02*
Y165450D01*
X87358D01*
X87052Y165295D01*
X86860Y165088D01*
X86783Y164675D01*
X86860Y164262D01*
X87090Y164003D01*
X87358Y163848D01*
X88317D01*
G01X87358D02*
X86783Y162350D01*
G01X84450D02*
Y165450D01*
X84910Y164830D01*
G01Y162350D02*
X83990D01*
G01X80890D02*
Y165450D01*
X82308Y163228D01*
X80392D01*
G01X78327Y162350D02*
X78250Y163022D01*
X78135Y163590D01*
X77982Y164107D01*
X77790Y164675D01*
X77483Y165450D01*
X79017D01*
G01X86767Y157850D02*
Y160950D01*
X85808D01*
X85502Y160795D01*
X85310Y160588D01*
X85233Y160175D01*
X85310Y159762D01*
X85540Y159503D01*
X85808Y159348D01*
X86767D01*
G01X85808D02*
X85233Y157850D01*
G01X83628Y160433D02*
X83398Y160743D01*
X83130Y160898D01*
X82823Y160950D01*
X82440Y160847D01*
X82172Y160588D01*
X82095Y160278D01*
X82133Y159968D01*
X82287Y159710D01*
X83053Y159193D01*
X83398Y158832D01*
X83628Y158315D01*
X83705Y157850D01*
X82095D01*
G01X80528Y159142D02*
X80260Y159503D01*
X80030Y159710D01*
X79723Y159813D01*
X79455Y159710D01*
X79263Y159503D01*
X79110Y159193D01*
X79072Y158832D01*
X79110Y158522D01*
X79263Y158212D01*
X79493Y157953D01*
X79762Y157850D01*
X80068Y157953D01*
X80337Y158263D01*
X80490Y158728D01*
X80528Y159245D01*
X80452Y159917D01*
X80337Y160278D01*
X80145Y160640D01*
X79877Y160898D01*
X79608Y160950D01*
X79340Y160847D01*
X79148Y160588D01*
G01X86367Y148450D02*
Y151550D01*
X85408D01*
X85102Y151395D01*
X84910Y151188D01*
X84833Y150775D01*
X84910Y150362D01*
X85140Y150103D01*
X85408Y149948D01*
X86367D01*
G01X85408D02*
X84833Y148450D01*
G01X83228Y151033D02*
X82998Y151343D01*
X82730Y151498D01*
X82423Y151550D01*
X82040Y151447D01*
X81772Y151188D01*
X81695Y150878D01*
X81733Y150568D01*
X81887Y150310D01*
X82653Y149793D01*
X82998Y149432D01*
X83228Y148915D01*
X83305Y148450D01*
X81695D01*
G01X79477D02*
X79400Y149122D01*
X79285Y149690D01*
X79132Y150207D01*
X78940Y150775D01*
X78633Y151550D01*
X80167D01*
G01X73367Y147950D02*
Y151050D01*
X72408D01*
X72102Y150895D01*
X71910Y150688D01*
X71833Y150275D01*
X71910Y149862D01*
X72140Y149603D01*
X72408Y149448D01*
X73367D01*
G01X72408D02*
X71833Y147950D01*
G01X70343Y148415D02*
X70113Y148157D01*
X69845Y148002D01*
X69500Y147950D01*
X69155Y148053D01*
X68887Y148260D01*
X68695Y148622D01*
X68657Y149035D01*
X68733Y149448D01*
X68925Y149707D01*
X69193Y149913D01*
X69462Y149965D01*
X69730Y149913D01*
X70075Y149707D01*
X69960Y151050D01*
X68925D01*
G01X67052Y148312D02*
X66783Y148053D01*
X66477Y147950D01*
X66170Y148053D01*
X65902Y148363D01*
X65710Y148828D01*
X65633Y149293D01*
Y149862D01*
X65710Y150327D01*
X65902Y150740D01*
X66132Y150947D01*
X66400Y151050D01*
X66707Y150947D01*
X66937Y150740D01*
X67090Y150430D01*
X67167Y150017D01*
X67090Y149655D01*
X66898Y149293D01*
X66668Y149087D01*
X66400Y149035D01*
X66093Y149138D01*
X65863Y149397D01*
X65633Y149862D01*
G01X88317Y153350D02*
Y156450D01*
X87358D01*
X87052Y156295D01*
X86860Y156088D01*
X86783Y155675D01*
X86860Y155262D01*
X87090Y155003D01*
X87358Y154848D01*
X88317D01*
G01X87358D02*
X86783Y153350D01*
G01X84450D02*
Y156450D01*
X84910Y155830D01*
G01Y153350D02*
X83990D01*
G01X80890D02*
Y156450D01*
X82308Y154228D01*
X80392D01*
G01X78250Y153350D02*
X77982Y153402D01*
X77675Y153557D01*
X77483Y153815D01*
X77407Y154177D01*
X77483Y154538D01*
X77713Y154848D01*
X78058Y155003D01*
X78442D01*
X78672Y155107D01*
X78863Y155365D01*
X78940Y155727D01*
X78825Y156088D01*
X78557Y156347D01*
X78250Y156450D01*
X77943Y156347D01*
X77675Y156088D01*
X77560Y155727D01*
X77637Y155365D01*
X77828Y155107D01*
X78058Y155003D01*
X78442D01*
X78787Y154848D01*
X79017Y154538D01*
X79093Y154177D01*
X79017Y153815D01*
X78825Y153557D01*
X78518Y153402D01*
X78250Y153350D01*
G01X75117Y158350D02*
Y161450D01*
X74158D01*
X73852Y161295D01*
X73660Y161088D01*
X73583Y160675D01*
X73660Y160262D01*
X73890Y160003D01*
X74158Y159848D01*
X75117D01*
G01X74158D02*
X73583Y158350D01*
G01X71250D02*
Y161450D01*
X71710Y160830D01*
G01Y158350D02*
X70790D01*
G01X67690D02*
Y161450D01*
X69108Y159228D01*
X67192D01*
G01X64590Y158350D02*
Y161450D01*
X66008Y159228D01*
X64092D01*
G01X86767Y166850D02*
Y169950D01*
X85808D01*
X85502Y169795D01*
X85310Y169588D01*
X85233Y169175D01*
X85310Y168762D01*
X85540Y168503D01*
X85808Y168348D01*
X86767D01*
G01X85808D02*
X85233Y166850D01*
G01X83743Y167315D02*
X83513Y167057D01*
X83245Y166902D01*
X82900Y166850D01*
X82555Y166953D01*
X82287Y167160D01*
X82095Y167522D01*
X82057Y167935D01*
X82133Y168348D01*
X82325Y168607D01*
X82593Y168813D01*
X82862Y168865D01*
X83130Y168813D01*
X83475Y168607D01*
X83360Y169950D01*
X82325D01*
G01X79800Y166850D02*
X79532Y166902D01*
X79225Y167057D01*
X79033Y167315D01*
X78957Y167677D01*
X79033Y168038D01*
X79263Y168348D01*
X79608Y168503D01*
X79992D01*
X80222Y168607D01*
X80413Y168865D01*
X80490Y169227D01*
X80375Y169588D01*
X80107Y169847D01*
X79800Y169950D01*
X79493Y169847D01*
X79225Y169588D01*
X79110Y169227D01*
X79187Y168865D01*
X79378Y168607D01*
X79608Y168503D01*
X79992D01*
X80337Y168348D01*
X80567Y168038D01*
X80643Y167677D01*
X80567Y167315D01*
X80375Y167057D01*
X80068Y166902D01*
X79800Y166850D01*
G01X74450Y236883D02*
X77550D01*
Y237842D01*
X77395Y238148D01*
X77188Y238340D01*
X76775Y238417D01*
X76362Y238340D01*
X76103Y238110D01*
X75948Y237842D01*
Y236883D01*
G01Y237842D02*
X74450Y238417D01*
G01X75070Y239907D02*
X74708Y240137D01*
X74502Y240443D01*
X74450Y240788D01*
X74502Y241095D01*
X74760Y241402D01*
X75070Y241593D01*
X75380Y241632D01*
X75742Y241555D01*
X76000Y241287D01*
X76103Y241018D01*
Y240673D01*
G01Y241018D02*
X76258Y241248D01*
X76517Y241440D01*
X76827Y241517D01*
X77137Y241440D01*
X77395Y241248D01*
X77550Y240903D01*
X77498Y240558D01*
X77292Y240213D01*
G01X74450Y243850D02*
X77550D01*
X76930Y243390D01*
G01X74450D02*
Y244310D01*
G01X74915Y246107D02*
X74657Y246337D01*
X74502Y246605D01*
X74450Y246950D01*
X74553Y247295D01*
X74760Y247563D01*
X75122Y247755D01*
X75535Y247793D01*
X75948Y247717D01*
X76207Y247525D01*
X76413Y247257D01*
X76465Y246988D01*
X76413Y246720D01*
X76207Y246375D01*
X77550Y246490D01*
Y247525D01*
G01X78950Y236883D02*
X82050D01*
Y237842D01*
X81895Y238148D01*
X81688Y238340D01*
X81275Y238417D01*
X80862Y238340D01*
X80603Y238110D01*
X80448Y237842D01*
Y236883D01*
G01Y237842D02*
X78950Y238417D01*
G01X79570Y239907D02*
X79208Y240137D01*
X79002Y240443D01*
X78950Y240788D01*
X79002Y241095D01*
X79260Y241402D01*
X79570Y241593D01*
X79880Y241632D01*
X80242Y241555D01*
X80500Y241287D01*
X80603Y241018D01*
Y240673D01*
G01Y241018D02*
X80758Y241248D01*
X81017Y241440D01*
X81327Y241517D01*
X81637Y241440D01*
X81895Y241248D01*
X82050Y240903D01*
X81998Y240558D01*
X81792Y240213D01*
G01X78950Y243850D02*
X82050D01*
X81430Y243390D01*
G01X78950D02*
Y244310D01*
G01X80242Y246222D02*
X80603Y246490D01*
X80810Y246720D01*
X80913Y247027D01*
X80810Y247295D01*
X80603Y247487D01*
X80293Y247640D01*
X79932Y247678D01*
X79622Y247640D01*
X79312Y247487D01*
X79053Y247257D01*
X78950Y246988D01*
X79053Y246682D01*
X79363Y246413D01*
X79828Y246260D01*
X80345Y246222D01*
X81017Y246298D01*
X81378Y246413D01*
X81740Y246605D01*
X81998Y246873D01*
X82050Y247142D01*
X81947Y247410D01*
X81688Y247602D01*
G01X69950Y236883D02*
X73050D01*
Y237842D01*
X72895Y238148D01*
X72688Y238340D01*
X72275Y238417D01*
X71862Y238340D01*
X71603Y238110D01*
X71448Y237842D01*
Y236883D01*
G01Y237842D02*
X69950Y238417D01*
G01X72533Y240022D02*
X72843Y240252D01*
X72998Y240520D01*
X73050Y240827D01*
X72947Y241210D01*
X72688Y241478D01*
X72378Y241555D01*
X72068Y241517D01*
X71810Y241363D01*
X71293Y240597D01*
X70932Y240252D01*
X70415Y240022D01*
X69950Y239945D01*
Y241555D01*
G01Y243850D02*
X70002Y244118D01*
X70157Y244425D01*
X70415Y244617D01*
X70777Y244693D01*
X71138Y244617D01*
X71448Y244387D01*
X71603Y244042D01*
Y243658D01*
X71707Y243428D01*
X71965Y243237D01*
X72327Y243160D01*
X72688Y243275D01*
X72947Y243543D01*
X73050Y243850D01*
X72947Y244157D01*
X72688Y244425D01*
X72327Y244540D01*
X71965Y244463D01*
X71707Y244272D01*
X71603Y244042D01*
Y243658D01*
X71448Y243313D01*
X71138Y243083D01*
X70777Y243007D01*
X70415Y243083D01*
X70157Y243275D01*
X70002Y243582D01*
X69950Y243850D01*
G01X72533Y246222D02*
X72843Y246452D01*
X72998Y246720D01*
X73050Y247027D01*
X72947Y247410D01*
X72688Y247678D01*
X72378Y247755D01*
X72068Y247717D01*
X71810Y247563D01*
X71293Y246797D01*
X70932Y246452D01*
X70415Y246222D01*
X69950Y246145D01*
Y247755D01*
G01X63950Y298583D02*
X67050D01*
Y299542D01*
X66895Y299848D01*
X66688Y300040D01*
X66275Y300117D01*
X65862Y300040D01*
X65603Y299810D01*
X65448Y299542D01*
Y298583D01*
G01Y299542D02*
X63950Y300117D01*
G01X64570Y301607D02*
X64208Y301837D01*
X64002Y302143D01*
X63950Y302488D01*
X64002Y302795D01*
X64260Y303102D01*
X64570Y303293D01*
X64880Y303332D01*
X65242Y303255D01*
X65500Y302987D01*
X65603Y302718D01*
Y302373D01*
G01Y302718D02*
X65758Y302948D01*
X66017Y303140D01*
X66327Y303217D01*
X66637Y303140D01*
X66895Y302948D01*
X67050Y302603D01*
X66998Y302258D01*
X66792Y301913D01*
G01X64570Y304707D02*
X64208Y304937D01*
X64002Y305243D01*
X63950Y305588D01*
X64002Y305895D01*
X64260Y306202D01*
X64570Y306393D01*
X64880Y306432D01*
X65242Y306355D01*
X65500Y306087D01*
X65603Y305818D01*
Y305473D01*
G01Y305818D02*
X65758Y306048D01*
X66017Y306240D01*
X66327Y306317D01*
X66637Y306240D01*
X66895Y306048D01*
X67050Y305703D01*
X66998Y305358D01*
X66792Y305013D01*
G01X66533Y307922D02*
X66843Y308152D01*
X66998Y308420D01*
X67050Y308727D01*
X66947Y309110D01*
X66688Y309378D01*
X66378Y309455D01*
X66068Y309417D01*
X65810Y309263D01*
X65293Y308497D01*
X64932Y308152D01*
X64415Y307922D01*
X63950Y307845D01*
Y309455D01*
G01X77417Y290982D02*
Y294082D01*
X76458D01*
X76152Y293927D01*
X75960Y293720D01*
X75883Y293307D01*
X75960Y292894D01*
X76190Y292635D01*
X76458Y292480D01*
X77417D01*
G01X76458D02*
X75883Y290982D01*
G01X74393Y291602D02*
X74163Y291240D01*
X73857Y291034D01*
X73512Y290982D01*
X73205Y291034D01*
X72898Y291292D01*
X72707Y291602D01*
X72668Y291912D01*
X72745Y292274D01*
X73013Y292532D01*
X73282Y292635D01*
X73627D01*
G01X73282D02*
X73052Y292790D01*
X72860Y293049D01*
X72783Y293359D01*
X72860Y293669D01*
X73052Y293927D01*
X73397Y294082D01*
X73742Y294030D01*
X74087Y293824D01*
G01X69990Y290982D02*
Y294082D01*
X71408Y291860D01*
X69492D01*
G01X67350Y294082D02*
X67657Y293979D01*
X67887Y293720D01*
X68040Y293410D01*
X68155Y292997D01*
X68193Y292532D01*
X68155Y292067D01*
X68040Y291654D01*
X67887Y291344D01*
X67657Y291085D01*
X67350Y290982D01*
X67043Y291085D01*
X66813Y291344D01*
X66660Y291654D01*
X66545Y292067D01*
X66507Y292532D01*
X66545Y292997D01*
X66660Y293410D01*
X66813Y293720D01*
X67043Y293979D01*
X67350Y294082D01*
G01X77917Y318966D02*
Y322066D01*
X76958D01*
X76652Y321911D01*
X76460Y321704D01*
X76383Y321291D01*
X76460Y320878D01*
X76690Y320619D01*
X76958Y320464D01*
X77917D01*
G01X76958D02*
X76383Y318966D01*
G01X73590D02*
Y322066D01*
X75008Y319844D01*
X73092D01*
G01X71027Y318966D02*
X70950Y319638D01*
X70835Y320206D01*
X70682Y320723D01*
X70490Y321291D01*
X70183Y322066D01*
X71717D01*
G01X68502Y319328D02*
X68233Y319069D01*
X67927Y318966D01*
X67620Y319069D01*
X67352Y319379D01*
X67160Y319844D01*
X67083Y320309D01*
Y320878D01*
X67160Y321343D01*
X67352Y321756D01*
X67582Y321963D01*
X67850Y322066D01*
X68157Y321963D01*
X68387Y321756D01*
X68540Y321446D01*
X68617Y321033D01*
X68540Y320671D01*
X68348Y320309D01*
X68118Y320103D01*
X67850Y320051D01*
X67543Y320154D01*
X67313Y320413D01*
X67083Y320878D01*
G01X77917Y314466D02*
Y317566D01*
X76958D01*
X76652Y317411D01*
X76460Y317204D01*
X76383Y316791D01*
X76460Y316378D01*
X76690Y316119D01*
X76958Y315964D01*
X77917D01*
G01X76958D02*
X76383Y314466D01*
G01X73590D02*
Y317566D01*
X75008Y315344D01*
X73092D01*
G01X71027Y314466D02*
X70950Y315138D01*
X70835Y315706D01*
X70682Y316223D01*
X70490Y316791D01*
X70183Y317566D01*
X71717D01*
G01X68693Y315086D02*
X68463Y314724D01*
X68157Y314518D01*
X67812Y314466D01*
X67505Y314518D01*
X67198Y314776D01*
X67007Y315086D01*
X66968Y315396D01*
X67045Y315758D01*
X67313Y316016D01*
X67582Y316119D01*
X67927D01*
G01X67582D02*
X67352Y316274D01*
X67160Y316533D01*
X67083Y316843D01*
X67160Y317153D01*
X67352Y317411D01*
X67697Y317566D01*
X68042Y317514D01*
X68387Y317308D01*
G01X71808Y338243D02*
X71963Y338013D01*
X72066Y337745D01*
Y337438D01*
X71911Y337093D01*
X71653Y336825D01*
X71343Y336633D01*
X70826Y336480D01*
X70361Y336442D01*
X69896Y336518D01*
X69586Y336633D01*
X69276Y336863D01*
X69069Y337132D01*
X68966Y337400D01*
Y337668D01*
X69069Y337937D01*
X69224Y338167D01*
X69431Y338358D01*
G01X69328Y339848D02*
X69069Y340117D01*
X68966Y340423D01*
X69069Y340730D01*
X69379Y340998D01*
X69844Y341190D01*
X70309Y341267D01*
X70878D01*
X71343Y341190D01*
X71756Y340998D01*
X71963Y340768D01*
X72066Y340500D01*
X71963Y340193D01*
X71756Y339963D01*
X71446Y339810D01*
X71033Y339733D01*
X70671Y339810D01*
X70309Y340002D01*
X70103Y340232D01*
X70051Y340500D01*
X70154Y340807D01*
X70413Y341037D01*
X70878Y341267D01*
G01X68966Y344060D02*
X72066D01*
X69844Y342642D01*
Y344558D01*
G01X77917Y323466D02*
Y326566D01*
X76958D01*
X76652Y326411D01*
X76460Y326204D01*
X76383Y325791D01*
X76460Y325378D01*
X76690Y325119D01*
X76958Y324964D01*
X77917D01*
G01X76958D02*
X76383Y323466D01*
G01X73590D02*
Y326566D01*
X75008Y324344D01*
X73092D01*
G01X71027Y323466D02*
X70950Y324138D01*
X70835Y324706D01*
X70682Y325223D01*
X70490Y325791D01*
X70183Y326566D01*
X71717D01*
G01X67850Y323466D02*
X67582Y323518D01*
X67275Y323673D01*
X67083Y323931D01*
X67007Y324293D01*
X67083Y324654D01*
X67313Y324964D01*
X67658Y325119D01*
X68042D01*
X68272Y325223D01*
X68463Y325481D01*
X68540Y325843D01*
X68425Y326204D01*
X68157Y326463D01*
X67850Y326566D01*
X67543Y326463D01*
X67275Y326204D01*
X67160Y325843D01*
X67237Y325481D01*
X67428Y325223D01*
X67658Y325119D01*
X68042D01*
X68387Y324964D01*
X68617Y324654D01*
X68693Y324293D01*
X68617Y323931D01*
X68425Y323673D01*
X68118Y323518D01*
X67850Y323466D01*
G01X90667Y69450D02*
Y72550D01*
X89708D01*
X89402Y72395D01*
X89210Y72188D01*
X89133Y71775D01*
X89210Y71362D01*
X89440Y71103D01*
X89708Y70948D01*
X90667D01*
G01X89708D02*
X89133Y69450D01*
G01X87528Y72033D02*
X87298Y72343D01*
X87030Y72498D01*
X86723Y72550D01*
X86340Y72447D01*
X86072Y72188D01*
X85995Y71878D01*
X86033Y71568D01*
X86187Y71310D01*
X86953Y70793D01*
X87298Y70432D01*
X87528Y69915D01*
X87605Y69450D01*
X85995D01*
G01X83240D02*
Y72550D01*
X84658Y70328D01*
X82742D01*
G01X87292Y80493D02*
X87447Y80263D01*
X87550Y79995D01*
Y79688D01*
X87395Y79343D01*
X87137Y79075D01*
X86827Y78883D01*
X86310Y78730D01*
X85845Y78692D01*
X85380Y78768D01*
X85070Y78883D01*
X84760Y79113D01*
X84553Y79382D01*
X84450Y79650D01*
Y79918D01*
X84553Y80187D01*
X84708Y80417D01*
X84915Y80608D01*
G01X84450Y82750D02*
X87550D01*
X86930Y82290D01*
G01X84450D02*
Y83210D01*
G01X86250Y86783D02*
X89350D01*
Y87742D01*
X89195Y88048D01*
X88988Y88240D01*
X88575Y88317D01*
X88162Y88240D01*
X87903Y88010D01*
X87748Y87742D01*
Y86783D01*
G01Y87742D02*
X86250Y88317D01*
G01Y90650D02*
X89350D01*
X88730Y90190D01*
G01X86250D02*
Y91110D01*
G01X86715Y92907D02*
X86457Y93137D01*
X86302Y93405D01*
X86250Y93750D01*
X86353Y94095D01*
X86560Y94363D01*
X86922Y94555D01*
X87335Y94593D01*
X87748Y94517D01*
X88007Y94325D01*
X88213Y94057D01*
X88265Y93788D01*
X88213Y93520D01*
X88007Y93175D01*
X89350Y93290D01*
Y94325D01*
G01X86612Y96198D02*
X86353Y96467D01*
X86250Y96773D01*
X86353Y97080D01*
X86663Y97348D01*
X87128Y97540D01*
X87593Y97617D01*
X88162D01*
X88627Y97540D01*
X89040Y97348D01*
X89247Y97118D01*
X89350Y96850D01*
X89247Y96543D01*
X89040Y96313D01*
X88730Y96160D01*
X88317Y96083D01*
X87955Y96160D01*
X87593Y96352D01*
X87387Y96582D01*
X87335Y96850D01*
X87438Y97157D01*
X87697Y97387D01*
X88162Y97617D01*
G01X82266Y87783D02*
X85366D01*
Y88742D01*
X85211Y89048D01*
X85004Y89240D01*
X84591Y89317D01*
X84178Y89240D01*
X83919Y89010D01*
X83764Y88742D01*
Y87783D01*
G01Y88742D02*
X82266Y89317D01*
G01Y91650D02*
X85366D01*
X84746Y91190D01*
G01X82266D02*
Y92110D01*
G01X83558Y94022D02*
X83919Y94290D01*
X84126Y94520D01*
X84229Y94827D01*
X84126Y95095D01*
X83919Y95287D01*
X83609Y95440D01*
X83248Y95478D01*
X82938Y95440D01*
X82628Y95287D01*
X82369Y95057D01*
X82266Y94788D01*
X82369Y94482D01*
X82679Y94213D01*
X83144Y94060D01*
X83661Y94022D01*
X84333Y94098D01*
X84694Y94213D01*
X85056Y94405D01*
X85314Y94673D01*
X85366Y94942D01*
X85263Y95210D01*
X85004Y95402D01*
G01X82266Y97850D02*
X85366D01*
X84746Y97390D01*
G01X82266D02*
Y98310D01*
G01X88050Y236883D02*
X91150D01*
Y237842D01*
X90995Y238148D01*
X90788Y238340D01*
X90375Y238417D01*
X89962Y238340D01*
X89703Y238110D01*
X89548Y237842D01*
Y236883D01*
G01Y237842D02*
X88050Y238417D01*
G01X88670Y239907D02*
X88308Y240137D01*
X88102Y240443D01*
X88050Y240788D01*
X88102Y241095D01*
X88360Y241402D01*
X88670Y241593D01*
X88980Y241632D01*
X89342Y241555D01*
X89600Y241287D01*
X89703Y241018D01*
Y240673D01*
G01Y241018D02*
X89858Y241248D01*
X90117Y241440D01*
X90427Y241517D01*
X90737Y241440D01*
X90995Y241248D01*
X91150Y240903D01*
X91098Y240558D01*
X90892Y240213D01*
G01X88050Y243850D02*
X91150D01*
X90530Y243390D01*
G01X88050D02*
Y244310D01*
G01Y247410D02*
X91150D01*
X88928Y245992D01*
Y247908D01*
G01X83450Y236883D02*
X86550D01*
Y237842D01*
X86395Y238148D01*
X86188Y238340D01*
X85775Y238417D01*
X85362Y238340D01*
X85103Y238110D01*
X84948Y237842D01*
Y236883D01*
G01Y237842D02*
X83450Y238417D01*
G01X86033Y240022D02*
X86343Y240252D01*
X86498Y240520D01*
X86550Y240827D01*
X86447Y241210D01*
X86188Y241478D01*
X85878Y241555D01*
X85568Y241517D01*
X85310Y241363D01*
X84793Y240597D01*
X84432Y240252D01*
X83915Y240022D01*
X83450Y239945D01*
Y241555D01*
G01Y243850D02*
X83502Y244118D01*
X83657Y244425D01*
X83915Y244617D01*
X84277Y244693D01*
X84638Y244617D01*
X84948Y244387D01*
X85103Y244042D01*
Y243658D01*
X85207Y243428D01*
X85465Y243237D01*
X85827Y243160D01*
X86188Y243275D01*
X86447Y243543D01*
X86550Y243850D01*
X86447Y244157D01*
X86188Y244425D01*
X85827Y244540D01*
X85465Y244463D01*
X85207Y244272D01*
X85103Y244042D01*
Y243658D01*
X84948Y243313D01*
X84638Y243083D01*
X84277Y243007D01*
X83915Y243083D01*
X83657Y243275D01*
X83502Y243582D01*
X83450Y243850D01*
G01Y246950D02*
X86550D01*
X85930Y246490D01*
G01X83450D02*
Y247410D01*
G01X89250Y277133D02*
X92350D01*
Y278092D01*
X92195Y278398D01*
X91988Y278590D01*
X91575Y278667D01*
X91162Y278590D01*
X90903Y278360D01*
X90748Y278092D01*
Y277133D01*
G01Y278092D02*
X89250Y278667D01*
G01X89612Y280348D02*
X89353Y280617D01*
X89250Y280923D01*
X89353Y281230D01*
X89663Y281498D01*
X90128Y281690D01*
X90593Y281767D01*
X91162D01*
X91627Y281690D01*
X92040Y281498D01*
X92247Y281268D01*
X92350Y281000D01*
X92247Y280693D01*
X92040Y280463D01*
X91730Y280310D01*
X91317Y280233D01*
X90955Y280310D01*
X90593Y280502D01*
X90387Y280732D01*
X90335Y281000D01*
X90438Y281307D01*
X90697Y281537D01*
X91162Y281767D01*
G01X89250Y284100D02*
X92350D01*
X91730Y283640D01*
G01X89250D02*
Y284560D01*
G01X84766Y275583D02*
X87866D01*
Y276542D01*
X87711Y276848D01*
X87504Y277040D01*
X87091Y277117D01*
X86678Y277040D01*
X86419Y276810D01*
X86264Y276542D01*
Y275583D01*
G01Y276542D02*
X84766Y277117D01*
G01X85386Y278607D02*
X85024Y278837D01*
X84818Y279143D01*
X84766Y279488D01*
X84818Y279795D01*
X85076Y280102D01*
X85386Y280293D01*
X85696Y280332D01*
X86058Y280255D01*
X86316Y279987D01*
X86419Y279718D01*
Y279373D01*
G01Y279718D02*
X86574Y279948D01*
X86833Y280140D01*
X87143Y280217D01*
X87453Y280140D01*
X87711Y279948D01*
X87866Y279603D01*
X87814Y279258D01*
X87608Y278913D01*
G01X84766Y283010D02*
X87866D01*
X85644Y281592D01*
Y283508D01*
G01X85386Y284807D02*
X85024Y285037D01*
X84818Y285343D01*
X84766Y285688D01*
X84818Y285995D01*
X85076Y286302D01*
X85386Y286493D01*
X85696Y286532D01*
X86058Y286455D01*
X86316Y286187D01*
X86419Y285918D01*
Y285573D01*
G01Y285918D02*
X86574Y286148D01*
X86833Y286340D01*
X87143Y286417D01*
X87453Y286340D01*
X87711Y286148D01*
X87866Y285803D01*
X87814Y285458D01*
X87608Y285113D01*
G01X94417Y344466D02*
Y347566D01*
X93458D01*
X93152Y347411D01*
X92960Y347204D01*
X92883Y346791D01*
X92960Y346378D01*
X93190Y346119D01*
X93458Y345964D01*
X94417D01*
G01X93458D02*
X92883Y344466D01*
G01X90090D02*
Y347566D01*
X91508Y345344D01*
X89592D01*
G01X88178Y345758D02*
X87910Y346119D01*
X87680Y346326D01*
X87373Y346429D01*
X87105Y346326D01*
X86913Y346119D01*
X86760Y345809D01*
X86722Y345448D01*
X86760Y345138D01*
X86913Y344828D01*
X87143Y344569D01*
X87412Y344466D01*
X87718Y344569D01*
X87987Y344879D01*
X88140Y345344D01*
X88178Y345861D01*
X88102Y346533D01*
X87987Y346894D01*
X87795Y347256D01*
X87527Y347514D01*
X87258Y347566D01*
X86990Y347463D01*
X86798Y347204D01*
G01X85078Y345758D02*
X84810Y346119D01*
X84580Y346326D01*
X84273Y346429D01*
X84005Y346326D01*
X83813Y346119D01*
X83660Y345809D01*
X83622Y345448D01*
X83660Y345138D01*
X83813Y344828D01*
X84043Y344569D01*
X84312Y344466D01*
X84618Y344569D01*
X84887Y344879D01*
X85040Y345344D01*
X85078Y345861D01*
X85002Y346533D01*
X84887Y346894D01*
X84695Y347256D01*
X84427Y347514D01*
X84158Y347566D01*
X83890Y347463D01*
X83698Y347204D01*
G01X93966Y353083D02*
X97066D01*
Y354042D01*
X96911Y354348D01*
X96704Y354540D01*
X96291Y354617D01*
X95878Y354540D01*
X95619Y354310D01*
X95464Y354042D01*
Y353083D01*
G01Y354042D02*
X93966Y354617D01*
G01Y357410D02*
X97066D01*
X94844Y355992D01*
Y357908D01*
G01X95258Y359322D02*
X95619Y359590D01*
X95826Y359820D01*
X95929Y360127D01*
X95826Y360395D01*
X95619Y360587D01*
X95309Y360740D01*
X94948Y360778D01*
X94638Y360740D01*
X94328Y360587D01*
X94069Y360357D01*
X93966Y360088D01*
X94069Y359782D01*
X94379Y359513D01*
X94844Y359360D01*
X95361Y359322D01*
X96033Y359398D01*
X96394Y359513D01*
X96756Y359705D01*
X97014Y359973D01*
X97066Y360242D01*
X96963Y360510D01*
X96704Y360702D01*
G01X93966Y363073D02*
X94638Y363150D01*
X95206Y363265D01*
X95723Y363418D01*
X96291Y363610D01*
X97066Y363917D01*
Y362383D01*
G01X86950Y353583D02*
X90050D01*
Y354542D01*
X89895Y354848D01*
X89688Y355040D01*
X89275Y355117D01*
X88862Y355040D01*
X88603Y354810D01*
X88448Y354542D01*
Y353583D01*
G01Y354542D02*
X86950Y355117D01*
G01Y357910D02*
X90050D01*
X87828Y356492D01*
Y358408D01*
G01X88242Y359822D02*
X88603Y360090D01*
X88810Y360320D01*
X88913Y360627D01*
X88810Y360895D01*
X88603Y361087D01*
X88293Y361240D01*
X87932Y361278D01*
X87622Y361240D01*
X87312Y361087D01*
X87053Y360857D01*
X86950Y360588D01*
X87053Y360282D01*
X87363Y360013D01*
X87828Y359860D01*
X88345Y359822D01*
X89017Y359898D01*
X89378Y360013D01*
X89740Y360205D01*
X89998Y360473D01*
X90050Y360742D01*
X89947Y361010D01*
X89688Y361202D01*
G01X86950Y363650D02*
X87002Y363918D01*
X87157Y364225D01*
X87415Y364417D01*
X87777Y364493D01*
X88138Y364417D01*
X88448Y364187D01*
X88603Y363842D01*
Y363458D01*
X88707Y363228D01*
X88965Y363037D01*
X89327Y362960D01*
X89688Y363075D01*
X89947Y363343D01*
X90050Y363650D01*
X89947Y363957D01*
X89688Y364225D01*
X89327Y364340D01*
X88965Y364263D01*
X88707Y364072D01*
X88603Y363842D01*
Y363458D01*
X88448Y363113D01*
X88138Y362883D01*
X87777Y362807D01*
X87415Y362883D01*
X87157Y363075D01*
X87002Y363382D01*
X86950Y363650D01*
G01X94417Y348966D02*
Y352066D01*
X93458D01*
X93152Y351911D01*
X92960Y351704D01*
X92883Y351291D01*
X92960Y350878D01*
X93190Y350619D01*
X93458Y350464D01*
X94417D01*
G01X93458D02*
X92883Y348966D01*
G01X90090D02*
Y352066D01*
X91508Y349844D01*
X89592D01*
G01X88178Y350258D02*
X87910Y350619D01*
X87680Y350826D01*
X87373Y350929D01*
X87105Y350826D01*
X86913Y350619D01*
X86760Y350309D01*
X86722Y349948D01*
X86760Y349638D01*
X86913Y349328D01*
X87143Y349069D01*
X87412Y348966D01*
X87718Y349069D01*
X87987Y349379D01*
X88140Y349844D01*
X88178Y350361D01*
X88102Y351033D01*
X87987Y351394D01*
X87795Y351756D01*
X87527Y352014D01*
X87258Y352066D01*
X86990Y351963D01*
X86798Y351704D01*
G01X85002Y349328D02*
X84733Y349069D01*
X84427Y348966D01*
X84120Y349069D01*
X83852Y349379D01*
X83660Y349844D01*
X83583Y350309D01*
Y350878D01*
X83660Y351343D01*
X83852Y351756D01*
X84082Y351963D01*
X84350Y352066D01*
X84657Y351963D01*
X84887Y351756D01*
X85040Y351446D01*
X85117Y351033D01*
X85040Y350671D01*
X84848Y350309D01*
X84618Y350103D01*
X84350Y350051D01*
X84043Y350154D01*
X83813Y350413D01*
X83583Y350878D01*
G01X94417Y339966D02*
Y343066D01*
X93458D01*
X93152Y342911D01*
X92960Y342704D01*
X92883Y342291D01*
X92960Y341878D01*
X93190Y341619D01*
X93458Y341464D01*
X94417D01*
G01X93458D02*
X92883Y339966D01*
G01X90090D02*
Y343066D01*
X91508Y340844D01*
X89592D01*
G01X87527Y339966D02*
X87450Y340638D01*
X87335Y341206D01*
X87182Y341723D01*
X86990Y342291D01*
X86683Y343066D01*
X88217D01*
G01X84350D02*
X84657Y342963D01*
X84887Y342704D01*
X85040Y342394D01*
X85155Y341981D01*
X85193Y341516D01*
X85155Y341051D01*
X85040Y340638D01*
X84887Y340328D01*
X84657Y340069D01*
X84350Y339966D01*
X84043Y340069D01*
X83813Y340328D01*
X83660Y340638D01*
X83545Y341051D01*
X83507Y341516D01*
X83545Y341981D01*
X83660Y342394D01*
X83813Y342704D01*
X84043Y342963D01*
X84350Y343066D01*
G01X126447Y64320D02*
Y67420D01*
X125488D01*
X125182Y67265D01*
X124990Y67058D01*
X124913Y66645D01*
X124990Y66232D01*
X125220Y65973D01*
X125488Y65818D01*
X126447D01*
G01X125488D02*
X124913Y64320D01*
G01X122580D02*
Y67420D01*
X123040Y66800D01*
G01Y64320D02*
X122120D01*
G01X120132Y64682D02*
X119863Y64423D01*
X119557Y64320D01*
X119250Y64423D01*
X118982Y64733D01*
X118790Y65198D01*
X118713Y65663D01*
Y66232D01*
X118790Y66697D01*
X118982Y67110D01*
X119212Y67317D01*
X119480Y67420D01*
X119787Y67317D01*
X120017Y67110D01*
X120170Y66800D01*
X120247Y66387D01*
X120170Y66025D01*
X119978Y65663D01*
X119748Y65457D01*
X119480Y65405D01*
X119173Y65508D01*
X118943Y65767D01*
X118713Y66232D01*
G01X117032Y64682D02*
X116763Y64423D01*
X116457Y64320D01*
X116150Y64423D01*
X115882Y64733D01*
X115690Y65198D01*
X115613Y65663D01*
Y66232D01*
X115690Y66697D01*
X115882Y67110D01*
X116112Y67317D01*
X116380Y67420D01*
X116687Y67317D01*
X116917Y67110D01*
X117070Y66800D01*
X117147Y66387D01*
X117070Y66025D01*
X116878Y65663D01*
X116648Y65457D01*
X116380Y65405D01*
X116073Y65508D01*
X115843Y65767D01*
X115613Y66232D01*
G01X113280Y64320D02*
Y67420D01*
X113740Y66800D01*
G01Y64320D02*
X112820D01*
G01X111417Y70450D02*
Y73550D01*
X110458D01*
X110152Y73395D01*
X109960Y73188D01*
X109883Y72775D01*
X109960Y72362D01*
X110190Y72103D01*
X110458Y71948D01*
X111417D01*
G01X110458D02*
X109883Y70450D01*
G01X108393Y71070D02*
X108163Y70708D01*
X107857Y70502D01*
X107512Y70450D01*
X107205Y70502D01*
X106898Y70760D01*
X106707Y71070D01*
X106668Y71380D01*
X106745Y71742D01*
X107013Y72000D01*
X107282Y72103D01*
X107627D01*
G01X107282D02*
X107052Y72258D01*
X106860Y72517D01*
X106783Y72827D01*
X106860Y73137D01*
X107052Y73395D01*
X107397Y73550D01*
X107742Y73498D01*
X108087Y73292D01*
G01X103990Y70450D02*
Y73550D01*
X105408Y71328D01*
X103492D01*
G01X100890Y70450D02*
Y73550D01*
X102308Y71328D01*
X100392D01*
G01X105310Y309243D02*
X105465Y309013D01*
X105568Y308745D01*
Y308438D01*
X105413Y308093D01*
X105155Y307825D01*
X104845Y307633D01*
X104328Y307480D01*
X103863Y307442D01*
X103398Y307518D01*
X103088Y307633D01*
X102778Y307863D01*
X102571Y308132D01*
X102468Y308400D01*
Y308668D01*
X102571Y308937D01*
X102726Y309167D01*
X102933Y309358D01*
G01X102830Y310848D02*
X102571Y311117D01*
X102468Y311423D01*
X102571Y311730D01*
X102881Y311998D01*
X103346Y312190D01*
X103811Y312267D01*
X104380D01*
X104845Y312190D01*
X105258Y311998D01*
X105465Y311768D01*
X105568Y311500D01*
X105465Y311193D01*
X105258Y310963D01*
X104948Y310810D01*
X104535Y310733D01*
X104173Y310810D01*
X103811Y311002D01*
X103605Y311232D01*
X103553Y311500D01*
X103656Y311807D01*
X103915Y312037D01*
X104380Y312267D01*
G01X105568Y314600D02*
X105465Y314293D01*
X105206Y314063D01*
X104896Y313910D01*
X104483Y313795D01*
X104018Y313757D01*
X103553Y313795D01*
X103140Y313910D01*
X102830Y314063D01*
X102571Y314293D01*
X102468Y314600D01*
X102571Y314907D01*
X102830Y315137D01*
X103140Y315290D01*
X103553Y315405D01*
X104018Y315443D01*
X104483Y315405D01*
X104896Y315290D01*
X105206Y315137D01*
X105465Y314907D01*
X105568Y314600D01*
G01X114292Y354693D02*
X114447Y354463D01*
X114550Y354195D01*
Y353888D01*
X114395Y353543D01*
X114137Y353275D01*
X113827Y353083D01*
X113310Y352930D01*
X112845Y352892D01*
X112380Y352968D01*
X112070Y353083D01*
X111760Y353313D01*
X111553Y353582D01*
X111450Y353850D01*
Y354118D01*
X111553Y354387D01*
X111708Y354617D01*
X111915Y354808D01*
G01X111450Y356950D02*
X114550D01*
X113930Y356490D01*
G01X111450D02*
Y357410D01*
G01X114550Y360050D02*
X114447Y359743D01*
X114188Y359513D01*
X113878Y359360D01*
X113465Y359245D01*
X113000Y359207D01*
X112535Y359245D01*
X112122Y359360D01*
X111812Y359513D01*
X111553Y359743D01*
X111450Y360050D01*
X111553Y360357D01*
X111812Y360587D01*
X112122Y360740D01*
X112535Y360855D01*
X113000Y360893D01*
X113465Y360855D01*
X113878Y360740D01*
X114188Y360587D01*
X114447Y360357D01*
X114550Y360050D01*
G01Y363150D02*
X114447Y362843D01*
X114188Y362613D01*
X113878Y362460D01*
X113465Y362345D01*
X113000Y362307D01*
X112535Y362345D01*
X112122Y362460D01*
X111812Y362613D01*
X111553Y362843D01*
X111450Y363150D01*
X111553Y363457D01*
X111812Y363687D01*
X112122Y363840D01*
X112535Y363955D01*
X113000Y363993D01*
X113465Y363955D01*
X113878Y363840D01*
X114188Y363687D01*
X114447Y363457D01*
X114550Y363150D01*
G01X119757Y349824D02*
X119987Y349979D01*
X120255Y350082D01*
X120562D01*
X120907Y349927D01*
X121175Y349669D01*
X121367Y349359D01*
X121520Y348842D01*
X121558Y348377D01*
X121482Y347912D01*
X121367Y347602D01*
X121137Y347292D01*
X120868Y347085D01*
X120600Y346982D01*
X120332D01*
X120063Y347085D01*
X119833Y347240D01*
X119642Y347447D01*
G01X118152Y347344D02*
X117883Y347085D01*
X117577Y346982D01*
X117270Y347085D01*
X117002Y347395D01*
X116810Y347860D01*
X116733Y348325D01*
Y348894D01*
X116810Y349359D01*
X117002Y349772D01*
X117232Y349979D01*
X117500Y350082D01*
X117807Y349979D01*
X118037Y349772D01*
X118190Y349462D01*
X118267Y349049D01*
X118190Y348687D01*
X117998Y348325D01*
X117768Y348119D01*
X117500Y348067D01*
X117193Y348170D01*
X116963Y348429D01*
X116733Y348894D01*
G01X115243Y347447D02*
X115013Y347189D01*
X114745Y347034D01*
X114400Y346982D01*
X114055Y347085D01*
X113787Y347292D01*
X113595Y347654D01*
X113557Y348067D01*
X113633Y348480D01*
X113825Y348739D01*
X114093Y348945D01*
X114362Y348997D01*
X114630Y348945D01*
X114975Y348739D01*
X114860Y350082D01*
X113825D01*
G01X98466Y353083D02*
X101566D01*
Y354042D01*
X101411Y354348D01*
X101204Y354540D01*
X100791Y354617D01*
X100378Y354540D01*
X100119Y354310D01*
X99964Y354042D01*
Y353083D01*
G01Y354042D02*
X98466Y354617D01*
G01Y356950D02*
X101566D01*
X100946Y356490D01*
G01X98466D02*
Y357410D01*
G01X99086Y359207D02*
X98724Y359437D01*
X98518Y359743D01*
X98466Y360088D01*
X98518Y360395D01*
X98776Y360702D01*
X99086Y360893D01*
X99396Y360932D01*
X99758Y360855D01*
X100016Y360587D01*
X100119Y360318D01*
Y359973D01*
G01Y360318D02*
X100274Y360548D01*
X100533Y360740D01*
X100843Y360817D01*
X101153Y360740D01*
X101411Y360548D01*
X101566Y360203D01*
X101514Y359858D01*
X101308Y359513D01*
G01X101566Y363150D02*
X101463Y362843D01*
X101204Y362613D01*
X100894Y362460D01*
X100481Y362345D01*
X100016Y362307D01*
X99551Y362345D01*
X99138Y362460D01*
X98828Y362613D01*
X98569Y362843D01*
X98466Y363150D01*
X98569Y363457D01*
X98828Y363687D01*
X99138Y363840D01*
X99551Y363955D01*
X100016Y363993D01*
X100481Y363955D01*
X100894Y363840D01*
X101204Y363687D01*
X101463Y363457D01*
X101566Y363150D01*
G01X102968Y353083D02*
X106068D01*
Y354042D01*
X105913Y354348D01*
X105706Y354540D01*
X105293Y354617D01*
X104880Y354540D01*
X104621Y354310D01*
X104466Y354042D01*
Y353083D01*
G01Y354042D02*
X102968Y354617D01*
G01Y357410D02*
X106068D01*
X103846Y355992D01*
Y357908D01*
G01X104260Y359322D02*
X104621Y359590D01*
X104828Y359820D01*
X104931Y360127D01*
X104828Y360395D01*
X104621Y360587D01*
X104311Y360740D01*
X103950Y360778D01*
X103640Y360740D01*
X103330Y360587D01*
X103071Y360357D01*
X102968Y360088D01*
X103071Y359782D01*
X103381Y359513D01*
X103846Y359360D01*
X104363Y359322D01*
X105035Y359398D01*
X105396Y359513D01*
X105758Y359705D01*
X106016Y359973D01*
X106068Y360242D01*
X105965Y360510D01*
X105706Y360702D01*
G01X106068Y363150D02*
X105965Y362843D01*
X105706Y362613D01*
X105396Y362460D01*
X104983Y362345D01*
X104518Y362307D01*
X104053Y362345D01*
X103640Y362460D01*
X103330Y362613D01*
X103071Y362843D01*
X102968Y363150D01*
X103071Y363457D01*
X103330Y363687D01*
X103640Y363840D01*
X104053Y363955D01*
X104518Y363993D01*
X104983Y363955D01*
X105396Y363840D01*
X105706Y363687D01*
X105965Y363457D01*
X106068Y363150D01*
G01X110308Y356243D02*
X110463Y356013D01*
X110566Y355745D01*
Y355438D01*
X110411Y355093D01*
X110153Y354825D01*
X109843Y354633D01*
X109326Y354480D01*
X108861Y354442D01*
X108396Y354518D01*
X108086Y354633D01*
X107776Y354863D01*
X107569Y355132D01*
X107466Y355400D01*
Y355668D01*
X107569Y355937D01*
X107724Y356167D01*
X107931Y356358D01*
G01X107828Y357848D02*
X107569Y358117D01*
X107466Y358423D01*
X107569Y358730D01*
X107879Y358998D01*
X108344Y359190D01*
X108809Y359267D01*
X109378D01*
X109843Y359190D01*
X110256Y358998D01*
X110463Y358768D01*
X110566Y358500D01*
X110463Y358193D01*
X110256Y357963D01*
X109946Y357810D01*
X109533Y357733D01*
X109171Y357810D01*
X108809Y358002D01*
X108603Y358232D01*
X108551Y358500D01*
X108654Y358807D01*
X108913Y359037D01*
X109378Y359267D01*
G01X107466Y361600D02*
X107518Y361868D01*
X107673Y362175D01*
X107931Y362367D01*
X108293Y362443D01*
X108654Y362367D01*
X108964Y362137D01*
X109119Y361792D01*
Y361408D01*
X109223Y361178D01*
X109481Y360987D01*
X109843Y360910D01*
X110204Y361025D01*
X110463Y361293D01*
X110566Y361600D01*
X110463Y361907D01*
X110204Y362175D01*
X109843Y362290D01*
X109481Y362213D01*
X109223Y362022D01*
X109119Y361792D01*
Y361408D01*
X108964Y361063D01*
X108654Y360833D01*
X108293Y360757D01*
X107931Y360833D01*
X107673Y361025D01*
X107518Y361332D01*
X107466Y361600D01*
G01X111066Y346183D02*
X107966D01*
Y347717D01*
G01Y350510D02*
X111066D01*
X108844Y349092D01*
Y351008D01*
G01X103950Y367133D02*
X107050D01*
Y368092D01*
X106895Y368398D01*
X106688Y368590D01*
X106275Y368667D01*
X105862Y368590D01*
X105603Y368360D01*
X105448Y368092D01*
Y367133D01*
G01Y368092D02*
X103950Y368667D01*
G01Y371000D02*
X107050D01*
X106430Y370540D01*
G01X103950D02*
Y371460D01*
G01Y374100D02*
X104002Y374368D01*
X104157Y374675D01*
X104415Y374867D01*
X104777Y374943D01*
X105138Y374867D01*
X105448Y374637D01*
X105603Y374292D01*
Y373908D01*
X105707Y373678D01*
X105965Y373487D01*
X106327Y373410D01*
X106688Y373525D01*
X106947Y373793D01*
X107050Y374100D01*
X106947Y374407D01*
X106688Y374675D01*
X106327Y374790D01*
X105965Y374713D01*
X105707Y374522D01*
X105603Y374292D01*
Y373908D01*
X105448Y373563D01*
X105138Y373333D01*
X104777Y373257D01*
X104415Y373333D01*
X104157Y373525D01*
X104002Y373832D01*
X103950Y374100D01*
G01X138417Y74782D02*
Y77882D01*
X137458D01*
X137152Y77727D01*
X136960Y77520D01*
X136883Y77107D01*
X136960Y76694D01*
X137190Y76435D01*
X137458Y76280D01*
X138417D01*
G01X137458D02*
X136883Y74782D01*
G01X134550D02*
Y77882D01*
X135010Y77262D01*
G01Y74782D02*
X134090D01*
G01X132293Y75247D02*
X132063Y74989D01*
X131795Y74834D01*
X131450Y74782D01*
X131105Y74885D01*
X130837Y75092D01*
X130645Y75454D01*
X130607Y75867D01*
X130683Y76280D01*
X130875Y76539D01*
X131143Y76745D01*
X131412Y76797D01*
X131680Y76745D01*
X132025Y76539D01*
X131910Y77882D01*
X130875D01*
G01X128350Y74782D02*
X128082Y74834D01*
X127775Y74989D01*
X127583Y75247D01*
X127507Y75609D01*
X127583Y75970D01*
X127813Y76280D01*
X128158Y76435D01*
X128542D01*
X128772Y76539D01*
X128963Y76797D01*
X129040Y77159D01*
X128925Y77520D01*
X128657Y77779D01*
X128350Y77882D01*
X128043Y77779D01*
X127775Y77520D01*
X127660Y77159D01*
X127737Y76797D01*
X127928Y76539D01*
X128158Y76435D01*
X128542D01*
X128887Y76280D01*
X129117Y75970D01*
X129193Y75609D01*
X129117Y75247D01*
X128925Y74989D01*
X128618Y74834D01*
X128350Y74782D01*
G01X121787Y69310D02*
Y72410D01*
X120828D01*
X120522Y72255D01*
X120330Y72048D01*
X120253Y71635D01*
X120330Y71222D01*
X120560Y70963D01*
X120828Y70808D01*
X121787D01*
G01X120828D02*
X120253Y69310D01*
G01X117920D02*
Y72410D01*
X118380Y71790D01*
G01Y69310D02*
X117460D01*
G01X138367Y64250D02*
Y67350D01*
X137408D01*
X137102Y67195D01*
X136910Y66988D01*
X136833Y66575D01*
X136910Y66162D01*
X137140Y65903D01*
X137408Y65748D01*
X138367D01*
G01X137408D02*
X136833Y64250D01*
G01X134500D02*
Y67350D01*
X134960Y66730D01*
G01Y64250D02*
X134040D01*
G01X131477D02*
X131400Y64922D01*
X131285Y65490D01*
X131132Y66007D01*
X130940Y66575D01*
X130633Y67350D01*
X132167D01*
G01X129143Y64715D02*
X128913Y64457D01*
X128645Y64302D01*
X128300Y64250D01*
X127955Y64353D01*
X127687Y64560D01*
X127495Y64922D01*
X127457Y65335D01*
X127533Y65748D01*
X127725Y66007D01*
X127993Y66213D01*
X128262Y66265D01*
X128530Y66213D01*
X128875Y66007D01*
X128760Y67350D01*
X127725D01*
G01X138387Y69250D02*
Y72350D01*
X137428D01*
X137122Y72195D01*
X136930Y71988D01*
X136853Y71575D01*
X136930Y71162D01*
X137160Y70903D01*
X137428Y70748D01*
X138387D01*
G01X137428D02*
X136853Y69250D01*
G01X134520D02*
Y72350D01*
X134980Y71730D01*
G01Y69250D02*
X134060D01*
G01X131497D02*
X131420Y69922D01*
X131305Y70490D01*
X131152Y71007D01*
X130960Y71575D01*
X130653Y72350D01*
X132187D01*
G01X129048Y70542D02*
X128780Y70903D01*
X128550Y71110D01*
X128243Y71213D01*
X127975Y71110D01*
X127783Y70903D01*
X127630Y70593D01*
X127592Y70232D01*
X127630Y69922D01*
X127783Y69612D01*
X128013Y69353D01*
X128282Y69250D01*
X128588Y69353D01*
X128857Y69663D01*
X129010Y70128D01*
X129048Y70645D01*
X128972Y71317D01*
X128857Y71678D01*
X128665Y72040D01*
X128397Y72298D01*
X128128Y72350D01*
X127860Y72247D01*
X127668Y71988D01*
G01X127432Y308583D02*
X130532D01*
Y309542D01*
X130377Y309848D01*
X130170Y310040D01*
X129757Y310117D01*
X129344Y310040D01*
X129085Y309810D01*
X128930Y309542D01*
Y308583D01*
G01Y309542D02*
X127432Y310117D01*
G01Y312450D02*
X130532D01*
X129912Y311990D01*
G01X127432D02*
Y312910D01*
G01X128052Y314707D02*
X127690Y314937D01*
X127484Y315243D01*
X127432Y315588D01*
X127484Y315895D01*
X127742Y316202D01*
X128052Y316393D01*
X128362Y316432D01*
X128724Y316355D01*
X128982Y316087D01*
X129085Y315818D01*
Y315473D01*
G01Y315818D02*
X129240Y316048D01*
X129499Y316240D01*
X129809Y316317D01*
X130119Y316240D01*
X130377Y316048D01*
X130532Y315703D01*
X130480Y315358D01*
X130274Y315013D01*
G01X127432Y318650D02*
X130532D01*
X129912Y318190D01*
G01X127432D02*
Y319110D01*
G01X141417Y327482D02*
Y330582D01*
X140458D01*
X140152Y330427D01*
X139960Y330220D01*
X139883Y329807D01*
X139960Y329394D01*
X140190Y329135D01*
X140458Y328980D01*
X141417D01*
G01X140458D02*
X139883Y327482D01*
G01X137550D02*
Y330582D01*
X138010Y329962D01*
G01Y327482D02*
X137090D01*
G01X135293Y328102D02*
X135063Y327740D01*
X134757Y327534D01*
X134412Y327482D01*
X134105Y327534D01*
X133798Y327792D01*
X133607Y328102D01*
X133568Y328412D01*
X133645Y328774D01*
X133913Y329032D01*
X134182Y329135D01*
X134527D01*
G01X134182D02*
X133952Y329290D01*
X133760Y329549D01*
X133683Y329859D01*
X133760Y330169D01*
X133952Y330427D01*
X134297Y330582D01*
X134642Y330530D01*
X134987Y330324D01*
G01X132078Y330065D02*
X131848Y330375D01*
X131580Y330530D01*
X131273Y330582D01*
X130890Y330479D01*
X130622Y330220D01*
X130545Y329910D01*
X130583Y329600D01*
X130737Y329342D01*
X131503Y328825D01*
X131848Y328464D01*
X132078Y327947D01*
X132155Y327482D01*
X130545D01*
G01X141417Y322982D02*
Y326082D01*
X140458D01*
X140152Y325927D01*
X139960Y325720D01*
X139883Y325307D01*
X139960Y324894D01*
X140190Y324635D01*
X140458Y324480D01*
X141417D01*
G01X140458D02*
X139883Y322982D01*
G01X138393Y323602D02*
X138163Y323240D01*
X137857Y323034D01*
X137512Y322982D01*
X137205Y323034D01*
X136898Y323292D01*
X136707Y323602D01*
X136668Y323912D01*
X136745Y324274D01*
X137013Y324532D01*
X137282Y324635D01*
X137627D01*
G01X137282D02*
X137052Y324790D01*
X136860Y325049D01*
X136783Y325359D01*
X136860Y325669D01*
X137052Y325927D01*
X137397Y326082D01*
X137742Y326030D01*
X138087Y325824D01*
G01X133990Y322982D02*
Y326082D01*
X135408Y323860D01*
X133492D01*
G01X132002Y323344D02*
X131733Y323085D01*
X131427Y322982D01*
X131120Y323085D01*
X130852Y323395D01*
X130660Y323860D01*
X130583Y324325D01*
Y324894D01*
X130660Y325359D01*
X130852Y325772D01*
X131082Y325979D01*
X131350Y326082D01*
X131657Y325979D01*
X131887Y325772D01*
X132040Y325462D01*
X132117Y325049D01*
X132040Y324687D01*
X131848Y324325D01*
X131618Y324119D01*
X131350Y324067D01*
X131043Y324170D01*
X130813Y324429D01*
X130583Y324894D01*
G01X137757Y352324D02*
X137987Y352479D01*
X138255Y352582D01*
X138562D01*
X138907Y352427D01*
X139175Y352169D01*
X139367Y351859D01*
X139520Y351342D01*
X139558Y350877D01*
X139482Y350412D01*
X139367Y350102D01*
X139137Y349792D01*
X138868Y349585D01*
X138600Y349482D01*
X138332D01*
X138063Y349585D01*
X137833Y349740D01*
X137642Y349947D01*
G01X136152Y349844D02*
X135883Y349585D01*
X135577Y349482D01*
X135270Y349585D01*
X135002Y349895D01*
X134810Y350360D01*
X134733Y350825D01*
Y351394D01*
X134810Y351859D01*
X135002Y352272D01*
X135232Y352479D01*
X135500Y352582D01*
X135807Y352479D01*
X136037Y352272D01*
X136190Y351962D01*
X136267Y351549D01*
X136190Y351187D01*
X135998Y350825D01*
X135768Y350619D01*
X135500Y350567D01*
X135193Y350670D01*
X134963Y350929D01*
X134733Y351394D01*
G01X133128Y350774D02*
X132860Y351135D01*
X132630Y351342D01*
X132323Y351445D01*
X132055Y351342D01*
X131863Y351135D01*
X131710Y350825D01*
X131672Y350464D01*
X131710Y350154D01*
X131863Y349844D01*
X132093Y349585D01*
X132362Y349482D01*
X132668Y349585D01*
X132937Y349895D01*
X133090Y350360D01*
X133128Y350877D01*
X133052Y351549D01*
X132937Y351910D01*
X132745Y352272D01*
X132477Y352530D01*
X132208Y352582D01*
X131940Y352479D01*
X131748Y352220D01*
G01X128308Y354693D02*
X128463Y354463D01*
X128566Y354195D01*
Y353888D01*
X128411Y353543D01*
X128153Y353275D01*
X127843Y353083D01*
X127326Y352930D01*
X126861Y352892D01*
X126396Y352968D01*
X126086Y353083D01*
X125776Y353313D01*
X125569Y353582D01*
X125466Y353850D01*
Y354118D01*
X125569Y354387D01*
X125724Y354617D01*
X125931Y354808D01*
G01X125466Y356950D02*
X128566D01*
X127946Y356490D01*
G01X125466D02*
Y357410D01*
G01X128566Y360050D02*
X128463Y359743D01*
X128204Y359513D01*
X127894Y359360D01*
X127481Y359245D01*
X127016Y359207D01*
X126551Y359245D01*
X126138Y359360D01*
X125828Y359513D01*
X125569Y359743D01*
X125466Y360050D01*
X125569Y360357D01*
X125828Y360587D01*
X126138Y360740D01*
X126551Y360855D01*
X127016Y360893D01*
X127481Y360855D01*
X127894Y360740D01*
X128204Y360587D01*
X128463Y360357D01*
X128566Y360050D01*
G01X125466Y363150D02*
X128566D01*
X127946Y362690D01*
G01X125466D02*
Y363610D01*
G01X116466Y353083D02*
X119566D01*
Y354042D01*
X119411Y354348D01*
X119204Y354540D01*
X118791Y354617D01*
X118378Y354540D01*
X118119Y354310D01*
X117964Y354042D01*
Y353083D01*
G01Y354042D02*
X116466Y354617D01*
G01Y357410D02*
X119566D01*
X117344Y355992D01*
Y357908D01*
G01X117758Y359322D02*
X118119Y359590D01*
X118326Y359820D01*
X118429Y360127D01*
X118326Y360395D01*
X118119Y360587D01*
X117809Y360740D01*
X117448Y360778D01*
X117138Y360740D01*
X116828Y360587D01*
X116569Y360357D01*
X116466Y360088D01*
X116569Y359782D01*
X116879Y359513D01*
X117344Y359360D01*
X117861Y359322D01*
X118533Y359398D01*
X118894Y359513D01*
X119256Y359705D01*
X119514Y359973D01*
X119566Y360242D01*
X119463Y360510D01*
X119204Y360702D01*
G01X117086Y362307D02*
X116724Y362537D01*
X116518Y362843D01*
X116466Y363188D01*
X116518Y363495D01*
X116776Y363802D01*
X117086Y363993D01*
X117396Y364032D01*
X117758Y363955D01*
X118016Y363687D01*
X118119Y363418D01*
Y363073D01*
G01Y363418D02*
X118274Y363648D01*
X118533Y363840D01*
X118843Y363917D01*
X119153Y363840D01*
X119411Y363648D01*
X119566Y363303D01*
X119514Y362958D01*
X119308Y362613D01*
G01X123808Y356243D02*
X123963Y356013D01*
X124066Y355745D01*
Y355438D01*
X123911Y355093D01*
X123653Y354825D01*
X123343Y354633D01*
X122826Y354480D01*
X122361Y354442D01*
X121896Y354518D01*
X121586Y354633D01*
X121276Y354863D01*
X121069Y355132D01*
X120966Y355400D01*
Y355668D01*
X121069Y355937D01*
X121224Y356167D01*
X121431Y356358D01*
G01X121328Y357848D02*
X121069Y358117D01*
X120966Y358423D01*
X121069Y358730D01*
X121379Y358998D01*
X121844Y359190D01*
X122309Y359267D01*
X122878D01*
X123343Y359190D01*
X123756Y358998D01*
X123963Y358768D01*
X124066Y358500D01*
X123963Y358193D01*
X123756Y357963D01*
X123446Y357810D01*
X123033Y357733D01*
X122671Y357810D01*
X122309Y358002D01*
X122103Y358232D01*
X122051Y358500D01*
X122154Y358807D01*
X122413Y359037D01*
X122878Y359267D01*
G01X121328Y360948D02*
X121069Y361217D01*
X120966Y361523D01*
X121069Y361830D01*
X121379Y362098D01*
X121844Y362290D01*
X122309Y362367D01*
X122878D01*
X123343Y362290D01*
X123756Y362098D01*
X123963Y361868D01*
X124066Y361600D01*
X123963Y361293D01*
X123756Y361063D01*
X123446Y360910D01*
X123033Y360833D01*
X122671Y360910D01*
X122309Y361102D01*
X122103Y361332D01*
X122051Y361600D01*
X122154Y361907D01*
X122413Y362137D01*
X122878Y362367D01*
G01X134066Y353633D02*
X130966D01*
Y355167D01*
G01X133549Y356772D02*
X133859Y357002D01*
X134014Y357270D01*
X134066Y357577D01*
X133963Y357960D01*
X133704Y358228D01*
X133394Y358305D01*
X133084Y358267D01*
X132826Y358113D01*
X132309Y357347D01*
X131948Y357002D01*
X131431Y356772D01*
X130966Y356695D01*
Y358305D01*
G01X133549Y359872D02*
X133859Y360102D01*
X134014Y360370D01*
X134066Y360677D01*
X133963Y361060D01*
X133704Y361328D01*
X133394Y361405D01*
X133084Y361367D01*
X132826Y361213D01*
X132309Y360447D01*
X131948Y360102D01*
X131431Y359872D01*
X130966Y359795D01*
Y361405D01*
G01X155417Y298966D02*
Y302066D01*
X154458D01*
X154152Y301911D01*
X153960Y301704D01*
X153883Y301291D01*
X153960Y300878D01*
X154190Y300619D01*
X154458Y300464D01*
X155417D01*
G01X154458D02*
X153883Y298966D01*
G01X151090D02*
Y302066D01*
X152508Y299844D01*
X150592D01*
G01X149102Y299328D02*
X148833Y299069D01*
X148527Y298966D01*
X148220Y299069D01*
X147952Y299379D01*
X147760Y299844D01*
X147683Y300309D01*
Y300878D01*
X147760Y301343D01*
X147952Y301756D01*
X148182Y301963D01*
X148450Y302066D01*
X148757Y301963D01*
X148987Y301756D01*
X149140Y301446D01*
X149217Y301033D01*
X149140Y300671D01*
X148948Y300309D01*
X148718Y300103D01*
X148450Y300051D01*
X148143Y300154D01*
X147913Y300413D01*
X147683Y300878D01*
G01X145350Y298966D02*
Y302066D01*
X145810Y301446D01*
G01Y298966D02*
X144890D01*
G01X139308Y355743D02*
X139463Y355513D01*
X139566Y355245D01*
Y354938D01*
X139411Y354593D01*
X139153Y354325D01*
X138843Y354133D01*
X138326Y353980D01*
X137861Y353942D01*
X137396Y354018D01*
X137086Y354133D01*
X136776Y354363D01*
X136569Y354632D01*
X136466Y354900D01*
Y355168D01*
X136569Y355437D01*
X136724Y355667D01*
X136931Y355858D01*
G01X136828Y357348D02*
X136569Y357617D01*
X136466Y357923D01*
X136569Y358230D01*
X136879Y358498D01*
X137344Y358690D01*
X137809Y358767D01*
X138378D01*
X138843Y358690D01*
X139256Y358498D01*
X139463Y358268D01*
X139566Y358000D01*
X139463Y357693D01*
X139256Y357463D01*
X138946Y357310D01*
X138533Y357233D01*
X138171Y357310D01*
X137809Y357502D01*
X137603Y357732D01*
X137551Y358000D01*
X137654Y358307D01*
X137913Y358537D01*
X138378Y358767D01*
G01X136466Y361100D02*
X139566D01*
X138946Y360640D01*
G01X136466D02*
Y361560D01*
G01X151017Y388550D02*
Y391650D01*
X150058D01*
X149752Y391495D01*
X149560Y391288D01*
X149483Y390875D01*
X149560Y390462D01*
X149790Y390203D01*
X150058Y390048D01*
X151017D01*
G01X150058D02*
X149483Y388550D01*
G01X147150D02*
Y391650D01*
X147610Y391030D01*
G01Y388550D02*
X146690D01*
G01X143590D02*
Y391650D01*
X145008Y389428D01*
X143092D01*
G01X141678Y391133D02*
X141448Y391443D01*
X141180Y391598D01*
X140873Y391650D01*
X140490Y391547D01*
X140222Y391288D01*
X140145Y390978D01*
X140183Y390668D01*
X140337Y390410D01*
X141103Y389893D01*
X141448Y389532D01*
X141678Y389015D01*
X141755Y388550D01*
X140145D01*
G01X148467Y384066D02*
Y387166D01*
X147508D01*
X147202Y387011D01*
X147010Y386804D01*
X146933Y386391D01*
X147010Y385978D01*
X147240Y385719D01*
X147508Y385564D01*
X148467D01*
G01X147508D02*
X146933Y384066D01*
G01X144140D02*
Y387166D01*
X145558Y384944D01*
X143642D01*
G01X141577Y384066D02*
X141500Y384738D01*
X141385Y385306D01*
X141232Y385823D01*
X141040Y386391D01*
X140733Y387166D01*
X142267D01*
G01X147857Y404892D02*
X148087Y405047D01*
X148355Y405150D01*
X148662D01*
X149007Y404995D01*
X149275Y404737D01*
X149467Y404427D01*
X149620Y403910D01*
X149658Y403445D01*
X149582Y402980D01*
X149467Y402670D01*
X149237Y402360D01*
X148968Y402153D01*
X148700Y402050D01*
X148432D01*
X148163Y402153D01*
X147933Y402308D01*
X147742Y402515D01*
G01X145140Y402050D02*
Y405150D01*
X146558Y402928D01*
X144642D01*
G01X143228Y404633D02*
X142998Y404943D01*
X142730Y405098D01*
X142423Y405150D01*
X142040Y405047D01*
X141772Y404788D01*
X141695Y404478D01*
X141733Y404168D01*
X141887Y403910D01*
X142653Y403393D01*
X142998Y403032D01*
X143228Y402515D01*
X143305Y402050D01*
X141695D01*
G01X149467Y393050D02*
Y396150D01*
X148508D01*
X148202Y395995D01*
X148010Y395788D01*
X147933Y395375D01*
X148010Y394962D01*
X148240Y394703D01*
X148508Y394548D01*
X149467D01*
G01X148508D02*
X147933Y393050D01*
G01X145140D02*
Y396150D01*
X146558Y393928D01*
X144642D01*
G01X142500Y393050D02*
X142232Y393102D01*
X141925Y393257D01*
X141733Y393515D01*
X141657Y393877D01*
X141733Y394238D01*
X141963Y394548D01*
X142308Y394703D01*
X142692D01*
X142922Y394807D01*
X143113Y395065D01*
X143190Y395427D01*
X143075Y395788D01*
X142807Y396047D01*
X142500Y396150D01*
X142193Y396047D01*
X141925Y395788D01*
X141810Y395427D01*
X141887Y395065D01*
X142078Y394807D01*
X142308Y394703D01*
X142692D01*
X143037Y394548D01*
X143267Y394238D01*
X143343Y393877D01*
X143267Y393515D01*
X143075Y393257D01*
X142768Y393102D01*
X142500Y393050D01*
G01X149467Y397550D02*
Y400650D01*
X148508D01*
X148202Y400495D01*
X148010Y400288D01*
X147933Y399875D01*
X148010Y399462D01*
X148240Y399203D01*
X148508Y399048D01*
X149467D01*
G01X148508D02*
X147933Y397550D01*
G01X146443Y398170D02*
X146213Y397808D01*
X145907Y397602D01*
X145562Y397550D01*
X145255Y397602D01*
X144948Y397860D01*
X144757Y398170D01*
X144718Y398480D01*
X144795Y398842D01*
X145063Y399100D01*
X145332Y399203D01*
X145677D01*
G01X145332D02*
X145102Y399358D01*
X144910Y399617D01*
X144833Y399927D01*
X144910Y400237D01*
X145102Y400495D01*
X145447Y400650D01*
X145792Y400598D01*
X146137Y400392D01*
G01X142500Y400650D02*
X142807Y400547D01*
X143037Y400288D01*
X143190Y399978D01*
X143305Y399565D01*
X143343Y399100D01*
X143305Y398635D01*
X143190Y398222D01*
X143037Y397912D01*
X142807Y397653D01*
X142500Y397550D01*
X142193Y397653D01*
X141963Y397912D01*
X141810Y398222D01*
X141695Y398635D01*
X141657Y399100D01*
X141695Y399565D01*
X141810Y399978D01*
X141963Y400288D01*
X142193Y400547D01*
X142500Y400650D01*
G01X148367Y407450D02*
Y410550D01*
X147408D01*
X147102Y410395D01*
X146910Y410188D01*
X146833Y409775D01*
X146910Y409362D01*
X147140Y409103D01*
X147408Y408948D01*
X148367D01*
G01X147408D02*
X146833Y407450D01*
G01X145343Y407915D02*
X145113Y407657D01*
X144845Y407502D01*
X144500Y407450D01*
X144155Y407553D01*
X143887Y407760D01*
X143695Y408122D01*
X143657Y408535D01*
X143733Y408948D01*
X143925Y409207D01*
X144193Y409413D01*
X144462Y409465D01*
X144730Y409413D01*
X145075Y409207D01*
X144960Y410550D01*
X143925D01*
G01X141400D02*
X141707Y410447D01*
X141937Y410188D01*
X142090Y409878D01*
X142205Y409465D01*
X142243Y409000D01*
X142205Y408535D01*
X142090Y408122D01*
X141937Y407812D01*
X141707Y407553D01*
X141400Y407450D01*
X141093Y407553D01*
X140863Y407812D01*
X140710Y408122D01*
X140595Y408535D01*
X140557Y409000D01*
X140595Y409465D01*
X140710Y409878D01*
X140863Y410188D01*
X141093Y410447D01*
X141400Y410550D01*
G01X149467Y412650D02*
Y415750D01*
X148508D01*
X148202Y415595D01*
X148010Y415388D01*
X147933Y414975D01*
X148010Y414562D01*
X148240Y414303D01*
X148508Y414148D01*
X149467D01*
G01X148508D02*
X147933Y412650D01*
G01X146443Y413270D02*
X146213Y412908D01*
X145907Y412702D01*
X145562Y412650D01*
X145255Y412702D01*
X144948Y412960D01*
X144757Y413270D01*
X144718Y413580D01*
X144795Y413942D01*
X145063Y414200D01*
X145332Y414303D01*
X145677D01*
G01X145332D02*
X145102Y414458D01*
X144910Y414717D01*
X144833Y415027D01*
X144910Y415337D01*
X145102Y415595D01*
X145447Y415750D01*
X145792Y415698D01*
X146137Y415492D01*
G01X143228Y415233D02*
X142998Y415543D01*
X142730Y415698D01*
X142423Y415750D01*
X142040Y415647D01*
X141772Y415388D01*
X141695Y415078D01*
X141733Y414768D01*
X141887Y414510D01*
X142653Y413993D01*
X142998Y413632D01*
X143228Y413115D01*
X143305Y412650D01*
X141695D01*
G01X164292Y350243D02*
X164447Y350013D01*
X164550Y349745D01*
Y349438D01*
X164395Y349093D01*
X164137Y348825D01*
X163827Y348633D01*
X163310Y348480D01*
X162845Y348442D01*
X162380Y348518D01*
X162070Y348633D01*
X161760Y348863D01*
X161553Y349132D01*
X161450Y349400D01*
Y349668D01*
X161553Y349937D01*
X161708Y350167D01*
X161915Y350358D01*
G01X161450Y352500D02*
X161502Y352768D01*
X161657Y353075D01*
X161915Y353267D01*
X162277Y353343D01*
X162638Y353267D01*
X162948Y353037D01*
X163103Y352692D01*
Y352308D01*
X163207Y352078D01*
X163465Y351887D01*
X163827Y351810D01*
X164188Y351925D01*
X164447Y352193D01*
X164550Y352500D01*
X164447Y352807D01*
X164188Y353075D01*
X163827Y353190D01*
X163465Y353113D01*
X163207Y352922D01*
X163103Y352692D01*
Y352308D01*
X162948Y351963D01*
X162638Y351733D01*
X162277Y351657D01*
X161915Y351733D01*
X161657Y351925D01*
X161502Y352232D01*
X161450Y352500D01*
G01Y355600D02*
X161502Y355868D01*
X161657Y356175D01*
X161915Y356367D01*
X162277Y356443D01*
X162638Y356367D01*
X162948Y356137D01*
X163103Y355792D01*
Y355408D01*
X163207Y355178D01*
X163465Y354987D01*
X163827Y354910D01*
X164188Y355025D01*
X164447Y355293D01*
X164550Y355600D01*
X164447Y355907D01*
X164188Y356175D01*
X163827Y356290D01*
X163465Y356213D01*
X163207Y356022D01*
X163103Y355792D01*
Y355408D01*
X162948Y355063D01*
X162638Y354833D01*
X162277Y354757D01*
X161915Y354833D01*
X161657Y355025D01*
X161502Y355332D01*
X161450Y355600D01*
G01X159967Y376566D02*
Y379666D01*
X159008D01*
X158702Y379511D01*
X158510Y379304D01*
X158433Y378891D01*
X158510Y378478D01*
X158740Y378219D01*
X159008Y378064D01*
X159967D01*
G01X159008D02*
X158433Y376566D01*
G01X155640D02*
Y379666D01*
X157058Y377444D01*
X155142D01*
G01X153652Y376928D02*
X153383Y376669D01*
X153077Y376566D01*
X152770Y376669D01*
X152502Y376979D01*
X152310Y377444D01*
X152233Y377909D01*
Y378478D01*
X152310Y378943D01*
X152502Y379356D01*
X152732Y379563D01*
X153000Y379666D01*
X153307Y379563D01*
X153537Y379356D01*
X153690Y379046D01*
X153767Y378633D01*
X153690Y378271D01*
X153498Y377909D01*
X153268Y377703D01*
X153000Y377651D01*
X152693Y377754D01*
X152463Y378013D01*
X152233Y378478D01*
G01X168367Y387466D02*
Y390566D01*
X167408D01*
X167102Y390411D01*
X166910Y390204D01*
X166833Y389791D01*
X166910Y389378D01*
X167140Y389119D01*
X167408Y388964D01*
X168367D01*
G01X167408D02*
X166833Y387466D01*
G01X165343Y388086D02*
X165113Y387724D01*
X164807Y387518D01*
X164462Y387466D01*
X164155Y387518D01*
X163848Y387776D01*
X163657Y388086D01*
X163618Y388396D01*
X163695Y388758D01*
X163963Y389016D01*
X164232Y389119D01*
X164577D01*
G01X164232D02*
X164002Y389274D01*
X163810Y389533D01*
X163733Y389843D01*
X163810Y390153D01*
X164002Y390411D01*
X164347Y390566D01*
X164692Y390514D01*
X165037Y390308D01*
G01X161400Y387466D02*
Y390566D01*
X161860Y389946D01*
G01Y387466D02*
X160940D01*
G01X167005Y401963D02*
X166698Y401705D01*
X166353Y401550D01*
X166047D01*
X165740Y401705D01*
X165510Y401963D01*
X165395Y402325D01*
X165472Y402687D01*
X165663Y402997D01*
X166008Y403203D01*
X166468Y403307D01*
X166737Y403513D01*
X166852Y403875D01*
X166775Y404237D01*
X166583Y404495D01*
X166315Y404650D01*
X166047D01*
X165778Y404547D01*
X165548Y404288D01*
G01X163867Y401550D02*
Y404650D01*
X162947D01*
X162640Y404495D01*
X162410Y404133D01*
X162333Y403720D01*
X162410Y403307D01*
X162602Y402997D01*
X162947Y402842D01*
X163867D01*
G01X160000Y401550D02*
Y404650D01*
X160460Y404030D01*
G01Y401550D02*
X159540D01*
G01X182632Y27248D02*
X181674Y30348D01*
X180716Y27248D01*
G01X181061Y28333D02*
X182287D01*
G01X178574Y27248D02*
Y30348D01*
X179034Y29728D01*
G01Y27248D02*
X178114D01*
G01X184910Y58453D02*
X188010D01*
Y59412D01*
X187855Y59718D01*
X187648Y59910D01*
X187235Y59987D01*
X186822Y59910D01*
X186563Y59680D01*
X186408Y59412D01*
Y58453D01*
G01Y59412D02*
X184910Y59987D01*
G01X187493Y61592D02*
X187803Y61822D01*
X187958Y62090D01*
X188010Y62397D01*
X187907Y62780D01*
X187648Y63048D01*
X187338Y63125D01*
X187028Y63087D01*
X186770Y62933D01*
X186253Y62167D01*
X185892Y61822D01*
X185375Y61592D01*
X184910Y61515D01*
Y63125D01*
G01X185530Y64577D02*
X185168Y64807D01*
X184962Y65113D01*
X184910Y65458D01*
X184962Y65765D01*
X185220Y66072D01*
X185530Y66263D01*
X185840Y66302D01*
X186202Y66225D01*
X186460Y65957D01*
X186563Y65688D01*
Y65343D01*
G01Y65688D02*
X186718Y65918D01*
X186977Y66110D01*
X187287Y66187D01*
X187597Y66110D01*
X187855Y65918D01*
X188010Y65573D01*
X187958Y65228D01*
X187752Y64883D01*
G01X169443Y337765D02*
X169213Y337507D01*
X168945Y337352D01*
X168600Y337300D01*
X168255Y337403D01*
X167987Y337610D01*
X167795Y337972D01*
X167757Y338385D01*
X167833Y338798D01*
X168025Y339057D01*
X168293Y339263D01*
X168562Y339315D01*
X168830Y339263D01*
X169175Y339057D01*
X169060Y340400D01*
X168025D01*
G01X168700Y352300D02*
X168432Y352352D01*
X168125Y352507D01*
X167933Y352765D01*
X167857Y353127D01*
X167933Y353488D01*
X168163Y353798D01*
X168508Y353953D01*
X168892D01*
X169122Y354057D01*
X169313Y354315D01*
X169390Y354677D01*
X169275Y355038D01*
X169007Y355297D01*
X168700Y355400D01*
X168393Y355297D01*
X168125Y355038D01*
X168010Y354677D01*
X168087Y354315D01*
X168278Y354057D01*
X168508Y353953D01*
X168892D01*
X169237Y353798D01*
X169467Y353488D01*
X169543Y353127D01*
X169467Y352765D01*
X169275Y352507D01*
X168968Y352352D01*
X168700Y352300D01*
G01X189843Y349400D02*
Y347178D01*
X189690Y346713D01*
X189383Y346403D01*
X189000Y346300D01*
X188617Y346403D01*
X188310Y346713D01*
X188157Y347178D01*
Y349400D01*
G01X186743Y346920D02*
X186513Y346558D01*
X186207Y346352D01*
X185862Y346300D01*
X185555Y346352D01*
X185248Y346610D01*
X185057Y346920D01*
X185018Y347230D01*
X185095Y347592D01*
X185363Y347850D01*
X185632Y347953D01*
X185977D01*
G01X185632D02*
X185402Y348108D01*
X185210Y348367D01*
X185133Y348677D01*
X185210Y348987D01*
X185402Y349245D01*
X185747Y349400D01*
X186092Y349348D01*
X186437Y349142D01*
G01X182800Y346300D02*
Y349400D01*
X183260Y348780D01*
G01Y346300D02*
X182340D01*
G01X176757Y392292D02*
X176987Y392447D01*
X177255Y392550D01*
X177562D01*
X177907Y392395D01*
X178175Y392137D01*
X178367Y391827D01*
X178520Y391310D01*
X178558Y390845D01*
X178482Y390380D01*
X178367Y390070D01*
X178137Y389760D01*
X177868Y389553D01*
X177600Y389450D01*
X177332D01*
X177063Y389553D01*
X176833Y389708D01*
X176642Y389915D01*
G01X174040Y389450D02*
Y392550D01*
X175458Y390328D01*
X173542D01*
G01X170940Y389450D02*
Y392550D01*
X172358Y390328D01*
X170442D01*
G01X181292Y402243D02*
X181447Y402013D01*
X181550Y401745D01*
Y401438D01*
X181395Y401093D01*
X181137Y400825D01*
X180827Y400633D01*
X180310Y400480D01*
X179845Y400442D01*
X179380Y400518D01*
X179070Y400633D01*
X178760Y400863D01*
X178553Y401132D01*
X178450Y401400D01*
Y401668D01*
X178553Y401937D01*
X178708Y402167D01*
X178915Y402358D01*
G01X178450Y404960D02*
X181550D01*
X179328Y403542D01*
Y405458D01*
G01X178915Y406757D02*
X178657Y406987D01*
X178502Y407255D01*
X178450Y407600D01*
X178553Y407945D01*
X178760Y408213D01*
X179122Y408405D01*
X179535Y408443D01*
X179948Y408367D01*
X180207Y408175D01*
X180413Y407907D01*
X180465Y407638D01*
X180413Y407370D01*
X180207Y407025D01*
X181550Y407140D01*
Y408175D01*
G01X187867Y411450D02*
Y414550D01*
X186908D01*
X186602Y414395D01*
X186410Y414188D01*
X186333Y413775D01*
X186410Y413362D01*
X186640Y413103D01*
X186908Y412948D01*
X187867D01*
G01X186908D02*
X186333Y411450D01*
G01X184843Y412070D02*
X184613Y411708D01*
X184307Y411502D01*
X183962Y411450D01*
X183655Y411502D01*
X183348Y411760D01*
X183157Y412070D01*
X183118Y412380D01*
X183195Y412742D01*
X183463Y413000D01*
X183732Y413103D01*
X184077D01*
G01X183732D02*
X183502Y413258D01*
X183310Y413517D01*
X183233Y413827D01*
X183310Y414137D01*
X183502Y414395D01*
X183847Y414550D01*
X184192Y414498D01*
X184537Y414292D01*
G01X181743Y412070D02*
X181513Y411708D01*
X181207Y411502D01*
X180862Y411450D01*
X180555Y411502D01*
X180248Y411760D01*
X180057Y412070D01*
X180018Y412380D01*
X180095Y412742D01*
X180363Y413000D01*
X180632Y413103D01*
X180977D01*
G01X180632D02*
X180402Y413258D01*
X180210Y413517D01*
X180133Y413827D01*
X180210Y414137D01*
X180402Y414395D01*
X180747Y414550D01*
X181092Y414498D01*
X181437Y414292D01*
G01X187466Y290583D02*
X190566D01*
Y291542D01*
X190411Y291848D01*
X190204Y292040D01*
X189791Y292117D01*
X189378Y292040D01*
X189119Y291810D01*
X188964Y291542D01*
Y290583D01*
G01Y291542D02*
X187466Y292117D01*
G01Y294910D02*
X190566D01*
X188344Y293492D01*
Y295408D01*
G01X187466Y297550D02*
X187518Y297818D01*
X187673Y298125D01*
X187931Y298317D01*
X188293Y298393D01*
X188654Y298317D01*
X188964Y298087D01*
X189119Y297742D01*
Y297358D01*
X189223Y297128D01*
X189481Y296937D01*
X189843Y296860D01*
X190204Y296975D01*
X190463Y297243D01*
X190566Y297550D01*
X190463Y297857D01*
X190204Y298125D01*
X189843Y298240D01*
X189481Y298163D01*
X189223Y297972D01*
X189119Y297742D01*
Y297358D01*
X188964Y297013D01*
X188654Y296783D01*
X188293Y296707D01*
X187931Y296783D01*
X187673Y296975D01*
X187518Y297282D01*
X187466Y297550D01*
G01Y300650D02*
X187518Y300918D01*
X187673Y301225D01*
X187931Y301417D01*
X188293Y301493D01*
X188654Y301417D01*
X188964Y301187D01*
X189119Y300842D01*
Y300458D01*
X189223Y300228D01*
X189481Y300037D01*
X189843Y299960D01*
X190204Y300075D01*
X190463Y300343D01*
X190566Y300650D01*
X190463Y300957D01*
X190204Y301225D01*
X189843Y301340D01*
X189481Y301263D01*
X189223Y301072D01*
X189119Y300842D01*
Y300458D01*
X188964Y300113D01*
X188654Y299883D01*
X188293Y299807D01*
X187931Y299883D01*
X187673Y300075D01*
X187518Y300382D01*
X187466Y300650D01*
G01X216794Y59693D02*
X216949Y59463D01*
X217052Y59195D01*
Y58888D01*
X216897Y58543D01*
X216639Y58275D01*
X216329Y58083D01*
X215812Y57930D01*
X215347Y57892D01*
X214882Y57968D01*
X214572Y58083D01*
X214262Y58313D01*
X214055Y58582D01*
X213952Y58850D01*
Y59118D01*
X214055Y59387D01*
X214210Y59617D01*
X214417Y59808D01*
G01X216535Y61222D02*
X216845Y61452D01*
X217000Y61720D01*
X217052Y62027D01*
X216949Y62410D01*
X216690Y62678D01*
X216380Y62755D01*
X216070Y62717D01*
X215812Y62563D01*
X215295Y61797D01*
X214934Y61452D01*
X214417Y61222D01*
X213952Y61145D01*
Y62755D01*
G01Y65050D02*
X214004Y65318D01*
X214159Y65625D01*
X214417Y65817D01*
X214779Y65893D01*
X215140Y65817D01*
X215450Y65587D01*
X215605Y65242D01*
Y64858D01*
X215709Y64628D01*
X215967Y64437D01*
X216329Y64360D01*
X216690Y64475D01*
X216949Y64743D01*
X217052Y65050D01*
X216949Y65357D01*
X216690Y65625D01*
X216329Y65740D01*
X215967Y65663D01*
X215709Y65472D01*
X215605Y65242D01*
Y64858D01*
X215450Y64513D01*
X215140Y64283D01*
X214779Y64207D01*
X214417Y64283D01*
X214159Y64475D01*
X214004Y64782D01*
X213952Y65050D01*
G01X214314Y67498D02*
X214055Y67767D01*
X213952Y68073D01*
X214055Y68380D01*
X214365Y68648D01*
X214830Y68840D01*
X215295Y68917D01*
X215864D01*
X216329Y68840D01*
X216742Y68648D01*
X216949Y68418D01*
X217052Y68150D01*
X216949Y67843D01*
X216742Y67613D01*
X216432Y67460D01*
X216019Y67383D01*
X215657Y67460D01*
X215295Y67652D01*
X215089Y67882D01*
X215037Y68150D01*
X215140Y68457D01*
X215399Y68687D01*
X215864Y68917D01*
G01X221294Y59693D02*
X221449Y59463D01*
X221552Y59195D01*
Y58888D01*
X221397Y58543D01*
X221139Y58275D01*
X220829Y58083D01*
X220312Y57930D01*
X219847Y57892D01*
X219382Y57968D01*
X219072Y58083D01*
X218762Y58313D01*
X218555Y58582D01*
X218452Y58850D01*
Y59118D01*
X218555Y59387D01*
X218710Y59617D01*
X218917Y59808D01*
G01X221035Y61222D02*
X221345Y61452D01*
X221500Y61720D01*
X221552Y62027D01*
X221449Y62410D01*
X221190Y62678D01*
X220880Y62755D01*
X220570Y62717D01*
X220312Y62563D01*
X219795Y61797D01*
X219434Y61452D01*
X218917Y61222D01*
X218452Y61145D01*
Y62755D01*
G01X218814Y64398D02*
X218555Y64667D01*
X218452Y64973D01*
X218555Y65280D01*
X218865Y65548D01*
X219330Y65740D01*
X219795Y65817D01*
X220364D01*
X220829Y65740D01*
X221242Y65548D01*
X221449Y65318D01*
X221552Y65050D01*
X221449Y64743D01*
X221242Y64513D01*
X220932Y64360D01*
X220519Y64283D01*
X220157Y64360D01*
X219795Y64552D01*
X219589Y64782D01*
X219537Y65050D01*
X219640Y65357D01*
X219899Y65587D01*
X220364Y65817D01*
G01X221552Y68150D02*
X221449Y67843D01*
X221190Y67613D01*
X220880Y67460D01*
X220467Y67345D01*
X220002Y67307D01*
X219537Y67345D01*
X219124Y67460D01*
X218814Y67613D01*
X218555Y67843D01*
X218452Y68150D01*
X218555Y68457D01*
X218814Y68687D01*
X219124Y68840D01*
X219537Y68955D01*
X220002Y68993D01*
X220467Y68955D01*
X220880Y68840D01*
X221190Y68687D01*
X221449Y68457D01*
X221552Y68150D01*
G01X215752Y289783D02*
X218852D01*
Y290742D01*
X218697Y291048D01*
X218490Y291240D01*
X218077Y291317D01*
X217664Y291240D01*
X217405Y291010D01*
X217250Y290742D01*
Y289783D01*
G01Y290742D02*
X215752Y291317D01*
G01Y294110D02*
X218852D01*
X216630Y292692D01*
Y294608D01*
G01X215752Y296750D02*
X218852D01*
X218232Y296290D01*
G01X215752D02*
Y297210D01*
G01X217044Y299122D02*
X217405Y299390D01*
X217612Y299620D01*
X217715Y299927D01*
X217612Y300195D01*
X217405Y300387D01*
X217095Y300540D01*
X216734Y300578D01*
X216424Y300540D01*
X216114Y300387D01*
X215855Y300157D01*
X215752Y299888D01*
X215855Y299582D01*
X216165Y299313D01*
X216630Y299160D01*
X217147Y299122D01*
X217819Y299198D01*
X218180Y299313D01*
X218542Y299505D01*
X218800Y299773D01*
X218852Y300042D01*
X218749Y300310D01*
X218490Y300502D01*
G01X211252Y289783D02*
X214352D01*
Y290742D01*
X214197Y291048D01*
X213990Y291240D01*
X213577Y291317D01*
X213164Y291240D01*
X212905Y291010D01*
X212750Y290742D01*
Y289783D01*
G01Y290742D02*
X211252Y291317D01*
G01Y294110D02*
X214352D01*
X212130Y292692D01*
Y294608D01*
G01X211252Y296750D02*
X214352D01*
X213732Y296290D01*
G01X211252D02*
Y297210D01*
G01X211872Y299007D02*
X211510Y299237D01*
X211304Y299543D01*
X211252Y299888D01*
X211304Y300195D01*
X211562Y300502D01*
X211872Y300693D01*
X212182Y300732D01*
X212544Y300655D01*
X212802Y300387D01*
X212905Y300118D01*
Y299773D01*
G01Y300118D02*
X213060Y300348D01*
X213319Y300540D01*
X213629Y300617D01*
X213939Y300540D01*
X214197Y300348D01*
X214352Y300003D01*
X214300Y299658D01*
X214094Y299313D01*
G01X206752Y289783D02*
X209852D01*
Y290742D01*
X209697Y291048D01*
X209490Y291240D01*
X209077Y291317D01*
X208664Y291240D01*
X208405Y291010D01*
X208250Y290742D01*
Y289783D01*
G01Y290742D02*
X206752Y291317D01*
G01Y294110D02*
X209852D01*
X207630Y292692D01*
Y294608D01*
G01X209852Y296750D02*
X209749Y296443D01*
X209490Y296213D01*
X209180Y296060D01*
X208767Y295945D01*
X208302Y295907D01*
X207837Y295945D01*
X207424Y296060D01*
X207114Y296213D01*
X206855Y296443D01*
X206752Y296750D01*
X206855Y297057D01*
X207114Y297287D01*
X207424Y297440D01*
X207837Y297555D01*
X208302Y297593D01*
X208767Y297555D01*
X209180Y297440D01*
X209490Y297287D01*
X209749Y297057D01*
X209852Y296750D01*
G01X207114Y299198D02*
X206855Y299467D01*
X206752Y299773D01*
X206855Y300080D01*
X207165Y300348D01*
X207630Y300540D01*
X208095Y300617D01*
X208664D01*
X209129Y300540D01*
X209542Y300348D01*
X209749Y300118D01*
X209852Y299850D01*
X209749Y299543D01*
X209542Y299313D01*
X209232Y299160D01*
X208819Y299083D01*
X208457Y299160D01*
X208095Y299352D01*
X207889Y299582D01*
X207837Y299850D01*
X207940Y300157D01*
X208199Y300387D01*
X208664Y300617D01*
G01X218917Y333950D02*
Y337050D01*
X217958D01*
X217652Y336895D01*
X217460Y336688D01*
X217383Y336275D01*
X217460Y335862D01*
X217690Y335603D01*
X217958Y335448D01*
X218917D01*
G01X217958D02*
X217383Y333950D01*
G01X214590D02*
Y337050D01*
X216008Y334828D01*
X214092D01*
G01X211490Y333950D02*
Y337050D01*
X212908Y334828D01*
X210992D01*
G01X208390Y333950D02*
Y337050D01*
X209808Y334828D01*
X207892D01*
G01X202740Y336900D02*
Y340000D01*
X204158Y337778D01*
X202242D01*
G01X217917Y341450D02*
Y344550D01*
X216958D01*
X216652Y344395D01*
X216460Y344188D01*
X216383Y343775D01*
X216460Y343362D01*
X216690Y343103D01*
X216958Y342948D01*
X217917D01*
G01X216958D02*
X216383Y341450D01*
G01X213590D02*
Y344550D01*
X215008Y342328D01*
X213092D01*
G01X211793Y341915D02*
X211563Y341657D01*
X211295Y341502D01*
X210950Y341450D01*
X210605Y341553D01*
X210337Y341760D01*
X210145Y342122D01*
X210107Y342535D01*
X210183Y342948D01*
X210375Y343207D01*
X210643Y343413D01*
X210912Y343465D01*
X211180Y343413D01*
X211525Y343207D01*
X211410Y344550D01*
X210375D01*
G01X207390Y341450D02*
Y344550D01*
X208808Y342328D01*
X206892D01*
G01X217917Y353966D02*
Y357066D01*
X216958D01*
X216652Y356911D01*
X216460Y356704D01*
X216383Y356291D01*
X216460Y355878D01*
X216690Y355619D01*
X216958Y355464D01*
X217917D01*
G01X216958D02*
X216383Y353966D01*
G01X213590D02*
Y357066D01*
X215008Y354844D01*
X213092D01*
G01X210490Y353966D02*
Y357066D01*
X211908Y354844D01*
X209992D01*
G01X208578Y355258D02*
X208310Y355619D01*
X208080Y355826D01*
X207773Y355929D01*
X207505Y355826D01*
X207313Y355619D01*
X207160Y355309D01*
X207122Y354948D01*
X207160Y354638D01*
X207313Y354328D01*
X207543Y354069D01*
X207812Y353966D01*
X208118Y354069D01*
X208387Y354379D01*
X208540Y354844D01*
X208578Y355361D01*
X208502Y356033D01*
X208387Y356394D01*
X208195Y356756D01*
X207927Y357014D01*
X207658Y357066D01*
X207390Y356963D01*
X207198Y356704D01*
G01X217917Y348966D02*
Y352066D01*
X216958D01*
X216652Y351911D01*
X216460Y351704D01*
X216383Y351291D01*
X216460Y350878D01*
X216690Y350619D01*
X216958Y350464D01*
X217917D01*
G01X216958D02*
X216383Y348966D01*
G01X213590D02*
Y352066D01*
X215008Y349844D01*
X213092D01*
G01X210490Y348966D02*
Y352066D01*
X211908Y349844D01*
X209992D01*
G01X207927Y348966D02*
X207850Y349638D01*
X207735Y350206D01*
X207582Y350723D01*
X207390Y351291D01*
X207083Y352066D01*
X208617D01*
G01X240605Y58243D02*
X240760Y58013D01*
X240863Y57745D01*
Y57438D01*
X240708Y57093D01*
X240450Y56825D01*
X240140Y56633D01*
X239623Y56480D01*
X239158Y56442D01*
X238693Y56518D01*
X238383Y56633D01*
X238073Y56863D01*
X237866Y57132D01*
X237763Y57400D01*
Y57668D01*
X237866Y57937D01*
X238021Y58167D01*
X238228Y58358D01*
G01X240346Y59772D02*
X240656Y60002D01*
X240811Y60270D01*
X240863Y60577D01*
X240760Y60960D01*
X240501Y61228D01*
X240191Y61305D01*
X239881Y61267D01*
X239623Y61113D01*
X239106Y60347D01*
X238745Y60002D01*
X238228Y59772D01*
X237763Y59695D01*
Y61305D01*
G01X238383Y62757D02*
X238021Y62987D01*
X237815Y63293D01*
X237763Y63638D01*
X237815Y63945D01*
X238073Y64252D01*
X238383Y64443D01*
X238693Y64482D01*
X239055Y64405D01*
X239313Y64137D01*
X239416Y63868D01*
Y63523D01*
G01Y63868D02*
X239571Y64098D01*
X239830Y64290D01*
X240140Y64367D01*
X240450Y64290D01*
X240708Y64098D01*
X240863Y63753D01*
X240811Y63408D01*
X240605Y63063D01*
G01X235604Y58233D02*
X235759Y58003D01*
X235862Y57735D01*
Y57428D01*
X235707Y57083D01*
X235449Y56815D01*
X235139Y56623D01*
X234622Y56470D01*
X234157Y56432D01*
X233692Y56508D01*
X233382Y56623D01*
X233072Y56853D01*
X232865Y57122D01*
X232762Y57390D01*
Y57658D01*
X232865Y57927D01*
X233020Y58157D01*
X233227Y58348D01*
G01X232762Y60490D02*
X235862D01*
X235242Y60030D01*
G01X232762D02*
Y60950D01*
G01X233124Y62938D02*
X232865Y63207D01*
X232762Y63513D01*
X232865Y63820D01*
X233175Y64088D01*
X233640Y64280D01*
X234105Y64357D01*
X234674D01*
X235139Y64280D01*
X235552Y64088D01*
X235759Y63858D01*
X235862Y63590D01*
X235759Y63283D01*
X235552Y63053D01*
X235242Y62900D01*
X234829Y62823D01*
X234467Y62900D01*
X234105Y63092D01*
X233899Y63322D01*
X233847Y63590D01*
X233950Y63897D01*
X234209Y64127D01*
X234674Y64357D01*
G01X227631Y61352D02*
X224531D01*
Y62886D01*
G01X227114Y64491D02*
X227424Y64721D01*
X227579Y64989D01*
X227631Y65296D01*
X227528Y65679D01*
X227269Y65947D01*
X226959Y66024D01*
X226649Y65986D01*
X226391Y65832D01*
X225874Y65066D01*
X225513Y64721D01*
X224996Y64491D01*
X224531Y64414D01*
Y66024D01*
G01Y68319D02*
X227631D01*
X227011Y67859D01*
G01X224531D02*
Y68779D01*
G01X247412Y58243D02*
X247567Y58013D01*
X247670Y57745D01*
Y57438D01*
X247515Y57093D01*
X247257Y56825D01*
X246947Y56633D01*
X246430Y56480D01*
X245965Y56442D01*
X245500Y56518D01*
X245190Y56633D01*
X244880Y56863D01*
X244673Y57132D01*
X244570Y57400D01*
Y57668D01*
X244673Y57937D01*
X244828Y58167D01*
X245035Y58358D01*
G01X247153Y59772D02*
X247463Y60002D01*
X247618Y60270D01*
X247670Y60577D01*
X247567Y60960D01*
X247308Y61228D01*
X246998Y61305D01*
X246688Y61267D01*
X246430Y61113D01*
X245913Y60347D01*
X245552Y60002D01*
X245035Y59772D01*
X244570Y59695D01*
Y61305D01*
G01Y64060D02*
X247670D01*
X245448Y62642D01*
Y64558D01*
G01X252412Y58243D02*
X252567Y58013D01*
X252670Y57745D01*
Y57438D01*
X252515Y57093D01*
X252257Y56825D01*
X251947Y56633D01*
X251430Y56480D01*
X250965Y56442D01*
X250500Y56518D01*
X250190Y56633D01*
X249880Y56863D01*
X249673Y57132D01*
X249570Y57400D01*
Y57668D01*
X249673Y57937D01*
X249828Y58167D01*
X250035Y58358D01*
G01X252153Y59772D02*
X252463Y60002D01*
X252618Y60270D01*
X252670Y60577D01*
X252567Y60960D01*
X252308Y61228D01*
X251998Y61305D01*
X251688Y61267D01*
X251430Y61113D01*
X250913Y60347D01*
X250552Y60002D01*
X250035Y59772D01*
X249570Y59695D01*
Y61305D01*
G01X250035Y62757D02*
X249777Y62987D01*
X249622Y63255D01*
X249570Y63600D01*
X249673Y63945D01*
X249880Y64213D01*
X250242Y64405D01*
X250655Y64443D01*
X251068Y64367D01*
X251327Y64175D01*
X251533Y63907D01*
X251585Y63638D01*
X251533Y63370D01*
X251327Y63025D01*
X252670Y63140D01*
Y64175D01*
G01X241343Y215120D02*
X241113Y214758D01*
X240807Y214552D01*
X240462Y214500D01*
X240155Y214552D01*
X239848Y214810D01*
X239657Y215120D01*
X239618Y215430D01*
X239695Y215792D01*
X239963Y216050D01*
X240232Y216153D01*
X240577D01*
G01X240232D02*
X240002Y216308D01*
X239810Y216567D01*
X239733Y216877D01*
X239810Y217187D01*
X240002Y217445D01*
X240347Y217600D01*
X240692Y217548D01*
X241037Y217342D01*
G01X252502Y213633D02*
X255602D01*
Y214592D01*
X255447Y214898D01*
X255240Y215090D01*
X254827Y215167D01*
X254414Y215090D01*
X254155Y214860D01*
X254000Y214592D01*
Y213633D01*
G01Y214592D02*
X252502Y215167D01*
G01X252864Y216848D02*
X252605Y217117D01*
X252502Y217423D01*
X252605Y217730D01*
X252915Y217998D01*
X253380Y218190D01*
X253845Y218267D01*
X254414D01*
X254879Y218190D01*
X255292Y217998D01*
X255499Y217768D01*
X255602Y217500D01*
X255499Y217193D01*
X255292Y216963D01*
X254982Y216810D01*
X254569Y216733D01*
X254207Y216810D01*
X253845Y217002D01*
X253639Y217232D01*
X253587Y217500D01*
X253690Y217807D01*
X253949Y218037D01*
X254414Y218267D01*
G01X252864Y219948D02*
X252605Y220217D01*
X252502Y220523D01*
X252605Y220830D01*
X252915Y221098D01*
X253380Y221290D01*
X253845Y221367D01*
X254414D01*
X254879Y221290D01*
X255292Y221098D01*
X255499Y220868D01*
X255602Y220600D01*
X255499Y220293D01*
X255292Y220063D01*
X254982Y219910D01*
X254569Y219833D01*
X254207Y219910D01*
X253845Y220102D01*
X253639Y220332D01*
X253587Y220600D01*
X253690Y220907D01*
X253949Y221137D01*
X254414Y221367D01*
G01X245552Y220057D02*
X243330D01*
X242865Y220210D01*
X242555Y220517D01*
X242452Y220900D01*
X242555Y221283D01*
X242865Y221590D01*
X243330Y221743D01*
X245552D01*
G01X242452Y224000D02*
X245552D01*
X244932Y223540D01*
G01X242452D02*
Y224460D01*
G01X245552Y227100D02*
X245449Y226793D01*
X245190Y226563D01*
X244880Y226410D01*
X244467Y226295D01*
X244002Y226257D01*
X243537Y226295D01*
X243124Y226410D01*
X242814Y226563D01*
X242555Y226793D01*
X242452Y227100D01*
X242555Y227407D01*
X242814Y227637D01*
X243124Y227790D01*
X243537Y227905D01*
X244002Y227943D01*
X244467Y227905D01*
X244880Y227790D01*
X245190Y227637D01*
X245449Y227407D01*
X245552Y227100D01*
G01X242095Y229618D02*
Y232718D01*
X243513Y230496D01*
X241597D01*
G01X248810Y229965D02*
X248580Y229707D01*
X248312Y229552D01*
X247967Y229500D01*
X247622Y229603D01*
X247354Y229810D01*
X247162Y230172D01*
X247124Y230585D01*
X247200Y230998D01*
X247392Y231257D01*
X247660Y231463D01*
X247929Y231515D01*
X248197Y231463D01*
X248542Y231257D01*
X248427Y232600D01*
X247392D01*
G01X244257Y236842D02*
X244487Y236997D01*
X244755Y237100D01*
X245062D01*
X245407Y236945D01*
X245675Y236687D01*
X245867Y236377D01*
X246020Y235860D01*
X246058Y235395D01*
X245982Y234930D01*
X245867Y234620D01*
X245637Y234310D01*
X245368Y234103D01*
X245100Y234000D01*
X244832D01*
X244563Y234103D01*
X244333Y234258D01*
X244142Y234465D01*
G01X242728Y235292D02*
X242460Y235653D01*
X242230Y235860D01*
X241923Y235963D01*
X241655Y235860D01*
X241463Y235653D01*
X241310Y235343D01*
X241272Y234982D01*
X241310Y234672D01*
X241463Y234362D01*
X241693Y234103D01*
X241962Y234000D01*
X242268Y234103D01*
X242537Y234413D01*
X242690Y234878D01*
X242728Y235395D01*
X242652Y236067D01*
X242537Y236428D01*
X242345Y236790D01*
X242077Y237048D01*
X241808Y237100D01*
X241540Y236997D01*
X241348Y236738D01*
G01X238900Y234000D02*
X238632Y234052D01*
X238325Y234207D01*
X238133Y234465D01*
X238057Y234827D01*
X238133Y235188D01*
X238363Y235498D01*
X238708Y235653D01*
X239092D01*
X239322Y235757D01*
X239513Y236015D01*
X239590Y236377D01*
X239475Y236738D01*
X239207Y236997D01*
X238900Y237100D01*
X238593Y236997D01*
X238325Y236738D01*
X238210Y236377D01*
X238287Y236015D01*
X238478Y235757D01*
X238708Y235653D01*
X239092D01*
X239437Y235498D01*
X239667Y235188D01*
X239743Y234827D01*
X239667Y234465D01*
X239475Y234207D01*
X239168Y234052D01*
X238900Y234000D01*
G01X252452Y223083D02*
X255552D01*
Y224042D01*
X255397Y224348D01*
X255190Y224540D01*
X254777Y224617D01*
X254364Y224540D01*
X254105Y224310D01*
X253950Y224042D01*
Y223083D01*
G01Y224042D02*
X252452Y224617D01*
G01Y226950D02*
X255552D01*
X254932Y226490D01*
G01X252452D02*
Y227410D01*
G01X255552Y230050D02*
X255449Y229743D01*
X255190Y229513D01*
X254880Y229360D01*
X254467Y229245D01*
X254002Y229207D01*
X253537Y229245D01*
X253124Y229360D01*
X252814Y229513D01*
X252555Y229743D01*
X252452Y230050D01*
X252555Y230357D01*
X252814Y230587D01*
X253124Y230740D01*
X253537Y230855D01*
X254002Y230893D01*
X254467Y230855D01*
X254880Y230740D01*
X255190Y230587D01*
X255449Y230357D01*
X255552Y230050D01*
G01Y233150D02*
X255449Y232843D01*
X255190Y232613D01*
X254880Y232460D01*
X254467Y232345D01*
X254002Y232307D01*
X253537Y232345D01*
X253124Y232460D01*
X252814Y232613D01*
X252555Y232843D01*
X252452Y233150D01*
X252555Y233457D01*
X252814Y233687D01*
X253124Y233840D01*
X253537Y233955D01*
X254002Y233993D01*
X254467Y233955D01*
X254880Y233840D01*
X255190Y233687D01*
X255449Y233457D01*
X255552Y233150D01*
G01X256917Y235500D02*
Y238600D01*
X255958D01*
X255652Y238445D01*
X255460Y238238D01*
X255383Y237825D01*
X255460Y237412D01*
X255690Y237153D01*
X255958Y236998D01*
X256917D01*
G01X255958D02*
X255383Y235500D01*
G01X253050D02*
Y238600D01*
X253510Y237980D01*
G01Y235500D02*
X252590D01*
G01X249950Y238600D02*
X250257Y238497D01*
X250487Y238238D01*
X250640Y237928D01*
X250755Y237515D01*
X250793Y237050D01*
X250755Y236585D01*
X250640Y236172D01*
X250487Y235862D01*
X250257Y235603D01*
X249950Y235500D01*
X249643Y235603D01*
X249413Y235862D01*
X249260Y236172D01*
X249145Y236585D01*
X249107Y237050D01*
X249145Y237515D01*
X249260Y237928D01*
X249413Y238238D01*
X249643Y238497D01*
X249950Y238600D01*
G01X246927Y235500D02*
X246850Y236172D01*
X246735Y236740D01*
X246582Y237257D01*
X246390Y237825D01*
X246083Y238600D01*
X247617D01*
G01X267099Y58243D02*
X267254Y58013D01*
X267357Y57745D01*
Y57438D01*
X267202Y57093D01*
X266944Y56825D01*
X266634Y56633D01*
X266117Y56480D01*
X265652Y56442D01*
X265187Y56518D01*
X264877Y56633D01*
X264567Y56863D01*
X264360Y57132D01*
X264257Y57400D01*
Y57668D01*
X264360Y57937D01*
X264515Y58167D01*
X264722Y58358D01*
G01X266840Y59772D02*
X267150Y60002D01*
X267305Y60270D01*
X267357Y60577D01*
X267254Y60960D01*
X266995Y61228D01*
X266685Y61305D01*
X266375Y61267D01*
X266117Y61113D01*
X265600Y60347D01*
X265239Y60002D01*
X264722Y59772D01*
X264257Y59695D01*
Y61305D01*
G01X265549Y62872D02*
X265910Y63140D01*
X266117Y63370D01*
X266220Y63677D01*
X266117Y63945D01*
X265910Y64137D01*
X265600Y64290D01*
X265239Y64328D01*
X264929Y64290D01*
X264619Y64137D01*
X264360Y63907D01*
X264257Y63638D01*
X264360Y63332D01*
X264670Y63063D01*
X265135Y62910D01*
X265652Y62872D01*
X266324Y62948D01*
X266685Y63063D01*
X267047Y63255D01*
X267305Y63523D01*
X267357Y63792D01*
X267254Y64060D01*
X266995Y64252D01*
G01X272099Y58243D02*
X272254Y58013D01*
X272357Y57745D01*
Y57438D01*
X272202Y57093D01*
X271944Y56825D01*
X271634Y56633D01*
X271117Y56480D01*
X270652Y56442D01*
X270187Y56518D01*
X269877Y56633D01*
X269567Y56863D01*
X269360Y57132D01*
X269257Y57400D01*
Y57668D01*
X269360Y57937D01*
X269515Y58167D01*
X269722Y58358D01*
G01X271840Y59772D02*
X272150Y60002D01*
X272305Y60270D01*
X272357Y60577D01*
X272254Y60960D01*
X271995Y61228D01*
X271685Y61305D01*
X271375Y61267D01*
X271117Y61113D01*
X270600Y60347D01*
X270239Y60002D01*
X269722Y59772D01*
X269257Y59695D01*
Y61305D01*
G01Y63523D02*
X269929Y63600D01*
X270497Y63715D01*
X271014Y63868D01*
X271582Y64060D01*
X272357Y64367D01*
Y62833D01*
G01X264620Y213157D02*
X264258Y213387D01*
X264052Y213693D01*
X264000Y214038D01*
X264052Y214345D01*
X264310Y214652D01*
X264620Y214843D01*
X264930Y214882D01*
X265292Y214805D01*
X265550Y214537D01*
X265653Y214268D01*
Y213923D01*
G01Y214268D02*
X265808Y214498D01*
X266067Y214690D01*
X266377Y214767D01*
X266687Y214690D01*
X266945Y214498D01*
X267100Y214153D01*
X267048Y213808D01*
X266842Y213463D01*
G01X260294Y226243D02*
X260449Y226013D01*
X260552Y225745D01*
Y225438D01*
X260397Y225093D01*
X260139Y224825D01*
X259829Y224633D01*
X259312Y224480D01*
X258847Y224442D01*
X258382Y224518D01*
X258072Y224633D01*
X257762Y224863D01*
X257555Y225132D01*
X257452Y225400D01*
Y225668D01*
X257555Y225937D01*
X257710Y226167D01*
X257917Y226358D01*
G01X258744Y227772D02*
X259105Y228040D01*
X259312Y228270D01*
X259415Y228577D01*
X259312Y228845D01*
X259105Y229037D01*
X258795Y229190D01*
X258434Y229228D01*
X258124Y229190D01*
X257814Y229037D01*
X257555Y228807D01*
X257452Y228538D01*
X257555Y228232D01*
X257865Y227963D01*
X258330Y227810D01*
X258847Y227772D01*
X259519Y227848D01*
X259880Y227963D01*
X260242Y228155D01*
X260500Y228423D01*
X260552Y228692D01*
X260449Y228960D01*
X260190Y229152D01*
G01X257814Y230948D02*
X257555Y231217D01*
X257452Y231523D01*
X257555Y231830D01*
X257865Y232098D01*
X258330Y232290D01*
X258795Y232367D01*
X259364D01*
X259829Y232290D01*
X260242Y232098D01*
X260449Y231868D01*
X260552Y231600D01*
X260449Y231293D01*
X260242Y231063D01*
X259932Y230910D01*
X259519Y230833D01*
X259157Y230910D01*
X258795Y231102D01*
X258589Y231332D01*
X258537Y231600D01*
X258640Y231907D01*
X258899Y232137D01*
X259364Y232367D01*
G01X270550Y221057D02*
X268328D01*
X267863Y221210D01*
X267553Y221517D01*
X267450Y221900D01*
X267553Y222283D01*
X267863Y222590D01*
X268328Y222743D01*
X270550D01*
G01X267450Y225000D02*
X270550D01*
X269930Y224540D01*
G01X267450D02*
Y225460D01*
G01X270033Y227372D02*
X270343Y227602D01*
X270498Y227870D01*
X270550Y228177D01*
X270447Y228560D01*
X270188Y228828D01*
X269878Y228905D01*
X269568Y228867D01*
X269310Y228713D01*
X268793Y227947D01*
X268432Y227602D01*
X267915Y227372D01*
X267450Y227295D01*
Y228905D01*
G01X265540Y232000D02*
Y235100D01*
X266958Y232878D01*
X265042D01*
G01X270917Y236000D02*
Y239100D01*
X269958D01*
X269652Y238945D01*
X269460Y238738D01*
X269383Y238325D01*
X269460Y237912D01*
X269690Y237653D01*
X269958Y237498D01*
X270917D01*
G01X269958D02*
X269383Y236000D01*
G01X267778Y238583D02*
X267548Y238893D01*
X267280Y239048D01*
X266973Y239100D01*
X266590Y238997D01*
X266322Y238738D01*
X266245Y238428D01*
X266283Y238118D01*
X266437Y237860D01*
X267203Y237343D01*
X267548Y236982D01*
X267778Y236465D01*
X267855Y236000D01*
X266245D01*
G01X264678Y237292D02*
X264410Y237653D01*
X264180Y237860D01*
X263873Y237963D01*
X263605Y237860D01*
X263413Y237653D01*
X263260Y237343D01*
X263222Y236982D01*
X263260Y236672D01*
X263413Y236362D01*
X263643Y236103D01*
X263912Y236000D01*
X264218Y236103D01*
X264487Y236413D01*
X264640Y236878D01*
X264678Y237395D01*
X264602Y238067D01*
X264487Y238428D01*
X264295Y238790D01*
X264027Y239048D01*
X263758Y239100D01*
X263490Y238997D01*
X263298Y238738D01*
G01X260927Y236000D02*
X260850Y236672D01*
X260735Y237240D01*
X260582Y237757D01*
X260390Y238325D01*
X260083Y239100D01*
X261617D01*
G01X281347Y58243D02*
X281502Y58013D01*
X281605Y57745D01*
Y57438D01*
X281450Y57093D01*
X281192Y56825D01*
X280882Y56633D01*
X280365Y56480D01*
X279900Y56442D01*
X279435Y56518D01*
X279125Y56633D01*
X278815Y56863D01*
X278608Y57132D01*
X278505Y57400D01*
Y57668D01*
X278608Y57937D01*
X278763Y58167D01*
X278970Y58358D01*
G01X281088Y59772D02*
X281398Y60002D01*
X281553Y60270D01*
X281605Y60577D01*
X281502Y60960D01*
X281243Y61228D01*
X280933Y61305D01*
X280623Y61267D01*
X280365Y61113D01*
X279848Y60347D01*
X279487Y60002D01*
X278970Y59772D01*
X278505Y59695D01*
Y61305D01*
G01Y63600D02*
X278557Y63868D01*
X278712Y64175D01*
X278970Y64367D01*
X279332Y64443D01*
X279693Y64367D01*
X280003Y64137D01*
X280158Y63792D01*
Y63408D01*
X280262Y63178D01*
X280520Y62987D01*
X280882Y62910D01*
X281243Y63025D01*
X281502Y63293D01*
X281605Y63600D01*
X281502Y63907D01*
X281243Y64175D01*
X280882Y64290D01*
X280520Y64213D01*
X280262Y64022D01*
X280158Y63792D01*
Y63408D01*
X280003Y63063D01*
X279693Y62833D01*
X279332Y62757D01*
X278970Y62833D01*
X278712Y63025D01*
X278557Y63332D01*
X278505Y63600D01*
G01X286347Y58243D02*
X286502Y58013D01*
X286605Y57745D01*
Y57438D01*
X286450Y57093D01*
X286192Y56825D01*
X285882Y56633D01*
X285365Y56480D01*
X284900Y56442D01*
X284435Y56518D01*
X284125Y56633D01*
X283815Y56863D01*
X283608Y57132D01*
X283505Y57400D01*
Y57668D01*
X283608Y57937D01*
X283763Y58167D01*
X283970Y58358D01*
G01X284125Y59657D02*
X283763Y59887D01*
X283557Y60193D01*
X283505Y60538D01*
X283557Y60845D01*
X283815Y61152D01*
X284125Y61343D01*
X284435Y61382D01*
X284797Y61305D01*
X285055Y61037D01*
X285158Y60768D01*
Y60423D01*
G01Y60768D02*
X285313Y60998D01*
X285572Y61190D01*
X285882Y61267D01*
X286192Y61190D01*
X286450Y60998D01*
X286605Y60653D01*
X286553Y60308D01*
X286347Y59963D01*
G01X283505Y64060D02*
X286605D01*
X284383Y62642D01*
Y64558D01*
G01X285617Y192950D02*
Y196050D01*
X284658D01*
X284352Y195895D01*
X284160Y195688D01*
X284083Y195275D01*
X284160Y194862D01*
X284390Y194603D01*
X284658Y194448D01*
X285617D01*
G01X284658D02*
X284083Y192950D01*
G01X281750D02*
X281482Y193002D01*
X281175Y193157D01*
X280983Y193415D01*
X280907Y193777D01*
X280983Y194138D01*
X281213Y194448D01*
X281558Y194603D01*
X281942D01*
X282172Y194707D01*
X282363Y194965D01*
X282440Y195327D01*
X282325Y195688D01*
X282057Y195947D01*
X281750Y196050D01*
X281443Y195947D01*
X281175Y195688D01*
X281060Y195327D01*
X281137Y194965D01*
X281328Y194707D01*
X281558Y194603D01*
X281942D01*
X282287Y194448D01*
X282517Y194138D01*
X282593Y193777D01*
X282517Y193415D01*
X282325Y193157D01*
X282018Y193002D01*
X281750Y192950D01*
G01X279302Y193312D02*
X279033Y193053D01*
X278727Y192950D01*
X278420Y193053D01*
X278152Y193363D01*
X277960Y193828D01*
X277883Y194293D01*
Y194862D01*
X277960Y195327D01*
X278152Y195740D01*
X278382Y195947D01*
X278650Y196050D01*
X278957Y195947D01*
X279187Y195740D01*
X279340Y195430D01*
X279417Y195017D01*
X279340Y194655D01*
X279148Y194293D01*
X278918Y194087D01*
X278650Y194035D01*
X278343Y194138D01*
X278113Y194397D01*
X277883Y194862D01*
G01X277950Y182033D02*
X281050D01*
Y182992D01*
X280895Y183298D01*
X280688Y183490D01*
X280275Y183567D01*
X279862Y183490D01*
X279603Y183260D01*
X279448Y182992D01*
Y182033D01*
G01Y182992D02*
X277950Y183567D01*
G01X278312Y185248D02*
X278053Y185517D01*
X277950Y185823D01*
X278053Y186130D01*
X278363Y186398D01*
X278828Y186590D01*
X279293Y186667D01*
X279862D01*
X280327Y186590D01*
X280740Y186398D01*
X280947Y186168D01*
X281050Y185900D01*
X280947Y185593D01*
X280740Y185363D01*
X280430Y185210D01*
X280017Y185133D01*
X279655Y185210D01*
X279293Y185402D01*
X279087Y185632D01*
X279035Y185900D01*
X279138Y186207D01*
X279397Y186437D01*
X279862Y186667D01*
G01X281050Y189000D02*
X280947Y188693D01*
X280688Y188463D01*
X280378Y188310D01*
X279965Y188195D01*
X279500Y188157D01*
X279035Y188195D01*
X278622Y188310D01*
X278312Y188463D01*
X278053Y188693D01*
X277950Y189000D01*
X278053Y189307D01*
X278312Y189537D01*
X278622Y189690D01*
X279035Y189805D01*
X279500Y189843D01*
X279965Y189805D01*
X280378Y189690D01*
X280688Y189537D01*
X280947Y189307D01*
X281050Y189000D01*
G01X280292Y216243D02*
X280447Y216013D01*
X280550Y215745D01*
Y215438D01*
X280395Y215093D01*
X280137Y214825D01*
X279827Y214633D01*
X279310Y214480D01*
X278845Y214442D01*
X278380Y214518D01*
X278070Y214633D01*
X277760Y214863D01*
X277553Y215132D01*
X277450Y215400D01*
Y215668D01*
X277553Y215937D01*
X277708Y216167D01*
X277915Y216358D01*
G01X277450Y218423D02*
X278122Y218500D01*
X278690Y218615D01*
X279207Y218768D01*
X279775Y218960D01*
X280550Y219267D01*
Y217733D01*
G01X277450Y221600D02*
X280550D01*
X279930Y221140D01*
G01X277450D02*
Y222060D01*
G01X282950Y215672D02*
X286050D01*
Y217128D01*
G01X284552Y216592D02*
Y215672D01*
G01X286050Y218657D02*
X283828D01*
X283363Y218810D01*
X283053Y219117D01*
X282950Y219500D01*
X283053Y219883D01*
X283363Y220190D01*
X283828Y220343D01*
X286050D01*
G01X283570Y221757D02*
X283208Y221987D01*
X283002Y222293D01*
X282950Y222638D01*
X283002Y222945D01*
X283260Y223252D01*
X283570Y223443D01*
X283880Y223482D01*
X284242Y223405D01*
X284500Y223137D01*
X284603Y222868D01*
Y222523D01*
G01Y222868D02*
X284758Y223098D01*
X285017Y223290D01*
X285327Y223367D01*
X285637Y223290D01*
X285895Y223098D01*
X286050Y222753D01*
X285998Y222408D01*
X285792Y222063D01*
G01X280292Y229443D02*
X280447Y229213D01*
X280550Y228945D01*
Y228638D01*
X280395Y228293D01*
X280137Y228025D01*
X279827Y227833D01*
X279310Y227680D01*
X278845Y227642D01*
X278380Y227718D01*
X278070Y227833D01*
X277760Y228063D01*
X277553Y228332D01*
X277450Y228600D01*
Y228868D01*
X277553Y229137D01*
X277708Y229367D01*
X277915Y229558D01*
G01X277450Y231623D02*
X278122Y231700D01*
X278690Y231815D01*
X279207Y231968D01*
X279775Y232160D01*
X280550Y232467D01*
Y230933D01*
G01Y234800D02*
X280447Y234493D01*
X280188Y234263D01*
X279878Y234110D01*
X279465Y233995D01*
X279000Y233957D01*
X278535Y233995D01*
X278122Y234110D01*
X277812Y234263D01*
X277553Y234493D01*
X277450Y234800D01*
X277553Y235107D01*
X277812Y235337D01*
X278122Y235490D01*
X278535Y235605D01*
X279000Y235643D01*
X279465Y235605D01*
X279878Y235490D01*
X280188Y235337D01*
X280447Y235107D01*
X280550Y234800D01*
G01X289450Y228133D02*
X292550D01*
Y229092D01*
X292395Y229398D01*
X292188Y229590D01*
X291775Y229667D01*
X291362Y229590D01*
X291103Y229360D01*
X290948Y229092D01*
Y228133D01*
G01Y229092D02*
X289450Y229667D01*
G01Y232460D02*
X292550D01*
X290328Y231042D01*
Y232958D01*
G01X289450Y235560D02*
X292550D01*
X290328Y234142D01*
Y236058D01*
G01X283450Y225583D02*
X286550D01*
Y226542D01*
X286395Y226848D01*
X286188Y227040D01*
X285775Y227117D01*
X285362Y227040D01*
X285103Y226810D01*
X284948Y226542D01*
Y225583D01*
G01Y226542D02*
X283450Y227117D01*
G01X284070Y228607D02*
X283708Y228837D01*
X283502Y229143D01*
X283450Y229488D01*
X283502Y229795D01*
X283760Y230102D01*
X284070Y230293D01*
X284380Y230332D01*
X284742Y230255D01*
X285000Y229987D01*
X285103Y229718D01*
Y229373D01*
G01Y229718D02*
X285258Y229948D01*
X285517Y230140D01*
X285827Y230217D01*
X286137Y230140D01*
X286395Y229948D01*
X286550Y229603D01*
X286498Y229258D01*
X286292Y228913D01*
G01X283915Y231707D02*
X283657Y231937D01*
X283502Y232205D01*
X283450Y232550D01*
X283553Y232895D01*
X283760Y233163D01*
X284122Y233355D01*
X284535Y233393D01*
X284948Y233317D01*
X285207Y233125D01*
X285413Y232857D01*
X285465Y232588D01*
X285413Y232320D01*
X285207Y231975D01*
X286550Y232090D01*
Y233125D01*
G01X283450Y235573D02*
X284122Y235650D01*
X284690Y235765D01*
X285207Y235918D01*
X285775Y236110D01*
X286550Y236417D01*
Y234883D01*
G01X274343Y232465D02*
X274113Y232207D01*
X273845Y232052D01*
X273500Y232000D01*
X273155Y232103D01*
X272887Y232310D01*
X272695Y232672D01*
X272657Y233085D01*
X272733Y233498D01*
X272925Y233757D01*
X273193Y233963D01*
X273462Y234015D01*
X273730Y233963D01*
X274075Y233757D01*
X273960Y235100D01*
X272925D01*
G01X291292Y284243D02*
X291447Y284013D01*
X291550Y283745D01*
Y283438D01*
X291395Y283093D01*
X291137Y282825D01*
X290827Y282633D01*
X290310Y282480D01*
X289845Y282442D01*
X289380Y282518D01*
X289070Y282633D01*
X288760Y282863D01*
X288553Y283132D01*
X288450Y283400D01*
Y283668D01*
X288553Y283937D01*
X288708Y284167D01*
X288915Y284358D01*
G01X289742Y285772D02*
X290103Y286040D01*
X290310Y286270D01*
X290413Y286577D01*
X290310Y286845D01*
X290103Y287037D01*
X289793Y287190D01*
X289432Y287228D01*
X289122Y287190D01*
X288812Y287037D01*
X288553Y286807D01*
X288450Y286538D01*
X288553Y286232D01*
X288863Y285963D01*
X289328Y285810D01*
X289845Y285772D01*
X290517Y285848D01*
X290878Y285963D01*
X291240Y286155D01*
X291498Y286423D01*
X291550Y286692D01*
X291447Y286960D01*
X291188Y287152D01*
G01X291550Y289600D02*
X291447Y289293D01*
X291188Y289063D01*
X290878Y288910D01*
X290465Y288795D01*
X290000Y288757D01*
X289535Y288795D01*
X289122Y288910D01*
X288812Y289063D01*
X288553Y289293D01*
X288450Y289600D01*
X288553Y289907D01*
X288812Y290137D01*
X289122Y290290D01*
X289535Y290405D01*
X290000Y290443D01*
X290465Y290405D01*
X290878Y290290D01*
X291188Y290137D01*
X291447Y289907D01*
X291550Y289600D01*
G01X286792Y284243D02*
X286947Y284013D01*
X287050Y283745D01*
Y283438D01*
X286895Y283093D01*
X286637Y282825D01*
X286327Y282633D01*
X285810Y282480D01*
X285345Y282442D01*
X284880Y282518D01*
X284570Y282633D01*
X284260Y282863D01*
X284053Y283132D01*
X283950Y283400D01*
Y283668D01*
X284053Y283937D01*
X284208Y284167D01*
X284415Y284358D01*
G01Y285657D02*
X284157Y285887D01*
X284002Y286155D01*
X283950Y286500D01*
X284053Y286845D01*
X284260Y287113D01*
X284622Y287305D01*
X285035Y287343D01*
X285448Y287267D01*
X285707Y287075D01*
X285913Y286807D01*
X285965Y286538D01*
X285913Y286270D01*
X285707Y285925D01*
X287050Y286040D01*
Y287075D01*
G01X284312Y288948D02*
X284053Y289217D01*
X283950Y289523D01*
X284053Y289830D01*
X284363Y290098D01*
X284828Y290290D01*
X285293Y290367D01*
X285862D01*
X286327Y290290D01*
X286740Y290098D01*
X286947Y289868D01*
X287050Y289600D01*
X286947Y289293D01*
X286740Y289063D01*
X286430Y288910D01*
X286017Y288833D01*
X285655Y288910D01*
X285293Y289102D01*
X285087Y289332D01*
X285035Y289600D01*
X285138Y289907D01*
X285397Y290137D01*
X285862Y290367D01*
G01X311058Y28000D02*
X310100Y31100D01*
X309142Y28000D01*
G01X309487Y29085D02*
X310713D01*
G01X307843Y28620D02*
X307613Y28258D01*
X307307Y28052D01*
X306962Y28000D01*
X306655Y28052D01*
X306348Y28310D01*
X306157Y28620D01*
X306118Y28930D01*
X306195Y29292D01*
X306463Y29550D01*
X306732Y29653D01*
X307077D01*
G01X306732D02*
X306502Y29808D01*
X306310Y30067D01*
X306233Y30377D01*
X306310Y30687D01*
X306502Y30945D01*
X306847Y31100D01*
X307192Y31048D01*
X307537Y30842D01*
G01X304628Y30583D02*
X304398Y30893D01*
X304130Y31048D01*
X303823Y31100D01*
X303440Y30997D01*
X303172Y30738D01*
X303095Y30428D01*
X303133Y30118D01*
X303287Y29860D01*
X304053Y29343D01*
X304398Y28982D01*
X304628Y28465D01*
X304705Y28000D01*
X303095D01*
G01X298595Y58243D02*
X298750Y58013D01*
X298853Y57745D01*
Y57438D01*
X298698Y57093D01*
X298440Y56825D01*
X298130Y56633D01*
X297613Y56480D01*
X297148Y56442D01*
X296683Y56518D01*
X296373Y56633D01*
X296063Y56863D01*
X295856Y57132D01*
X295753Y57400D01*
Y57668D01*
X295856Y57937D01*
X296011Y58167D01*
X296218Y58358D01*
G01X296373Y59657D02*
X296011Y59887D01*
X295805Y60193D01*
X295753Y60538D01*
X295805Y60845D01*
X296063Y61152D01*
X296373Y61343D01*
X296683Y61382D01*
X297045Y61305D01*
X297303Y61037D01*
X297406Y60768D01*
Y60423D01*
G01Y60768D02*
X297561Y60998D01*
X297820Y61190D01*
X298130Y61267D01*
X298440Y61190D01*
X298698Y60998D01*
X298853Y60653D01*
X298801Y60308D01*
X298595Y59963D01*
G01X296218Y62757D02*
X295960Y62987D01*
X295805Y63255D01*
X295753Y63600D01*
X295856Y63945D01*
X296063Y64213D01*
X296425Y64405D01*
X296838Y64443D01*
X297251Y64367D01*
X297510Y64175D01*
X297716Y63907D01*
X297768Y63638D01*
X297716Y63370D01*
X297510Y63025D01*
X298853Y63140D01*
Y64175D01*
G01X303595Y58243D02*
X303750Y58013D01*
X303853Y57745D01*
Y57438D01*
X303698Y57093D01*
X303440Y56825D01*
X303130Y56633D01*
X302613Y56480D01*
X302148Y56442D01*
X301683Y56518D01*
X301373Y56633D01*
X301063Y56863D01*
X300856Y57132D01*
X300753Y57400D01*
Y57668D01*
X300856Y57937D01*
X301011Y58167D01*
X301218Y58358D01*
G01X301373Y59657D02*
X301011Y59887D01*
X300805Y60193D01*
X300753Y60538D01*
X300805Y60845D01*
X301063Y61152D01*
X301373Y61343D01*
X301683Y61382D01*
X302045Y61305D01*
X302303Y61037D01*
X302406Y60768D01*
Y60423D01*
G01Y60768D02*
X302561Y60998D01*
X302820Y61190D01*
X303130Y61267D01*
X303440Y61190D01*
X303698Y60998D01*
X303853Y60653D01*
X303801Y60308D01*
X303595Y59963D01*
G01X302045Y62872D02*
X302406Y63140D01*
X302613Y63370D01*
X302716Y63677D01*
X302613Y63945D01*
X302406Y64137D01*
X302096Y64290D01*
X301735Y64328D01*
X301425Y64290D01*
X301115Y64137D01*
X300856Y63907D01*
X300753Y63638D01*
X300856Y63332D01*
X301166Y63063D01*
X301631Y62910D01*
X302148Y62872D01*
X302820Y62948D01*
X303181Y63063D01*
X303543Y63255D01*
X303801Y63523D01*
X303853Y63792D01*
X303750Y64060D01*
X303491Y64252D01*
G01X304257Y201792D02*
X304487Y201947D01*
X304755Y202050D01*
X305062D01*
X305407Y201895D01*
X305675Y201637D01*
X305867Y201327D01*
X306020Y200810D01*
X306058Y200345D01*
X305982Y199880D01*
X305867Y199570D01*
X305637Y199260D01*
X305368Y199053D01*
X305100Y198950D01*
X304832D01*
X304563Y199053D01*
X304333Y199208D01*
X304142Y199415D01*
G01X302728Y200242D02*
X302460Y200603D01*
X302230Y200810D01*
X301923Y200913D01*
X301655Y200810D01*
X301463Y200603D01*
X301310Y200293D01*
X301272Y199932D01*
X301310Y199622D01*
X301463Y199312D01*
X301693Y199053D01*
X301962Y198950D01*
X302268Y199053D01*
X302537Y199363D01*
X302690Y199828D01*
X302728Y200345D01*
X302652Y201017D01*
X302537Y201378D01*
X302345Y201740D01*
X302077Y201998D01*
X301808Y202050D01*
X301540Y201947D01*
X301348Y201688D01*
G01X299743Y199415D02*
X299513Y199157D01*
X299245Y199002D01*
X298900Y198950D01*
X298555Y199053D01*
X298287Y199260D01*
X298095Y199622D01*
X298057Y200035D01*
X298133Y200448D01*
X298325Y200707D01*
X298593Y200913D01*
X298862Y200965D01*
X299130Y200913D01*
X299475Y200707D01*
X299360Y202050D01*
X298325D01*
G01X305757Y195792D02*
X305987Y195947D01*
X306255Y196050D01*
X306562D01*
X306907Y195895D01*
X307175Y195637D01*
X307367Y195327D01*
X307520Y194810D01*
X307558Y194345D01*
X307482Y193880D01*
X307367Y193570D01*
X307137Y193260D01*
X306868Y193053D01*
X306600Y192950D01*
X306332D01*
X306063Y193053D01*
X305833Y193208D01*
X305642Y193415D01*
G01X304228Y194242D02*
X303960Y194603D01*
X303730Y194810D01*
X303423Y194913D01*
X303155Y194810D01*
X302963Y194603D01*
X302810Y194293D01*
X302772Y193932D01*
X302810Y193622D01*
X302963Y193312D01*
X303193Y193053D01*
X303462Y192950D01*
X303768Y193053D01*
X304037Y193363D01*
X304190Y193828D01*
X304228Y194345D01*
X304152Y195017D01*
X304037Y195378D01*
X303845Y195740D01*
X303577Y195998D01*
X303308Y196050D01*
X303040Y195947D01*
X302848Y195688D01*
G01X299940Y192950D02*
Y196050D01*
X301358Y193828D01*
X299442D01*
G01X304257Y206292D02*
X304487Y206447D01*
X304755Y206550D01*
X305062D01*
X305407Y206395D01*
X305675Y206137D01*
X305867Y205827D01*
X306020Y205310D01*
X306058Y204845D01*
X305982Y204380D01*
X305867Y204070D01*
X305637Y203760D01*
X305368Y203553D01*
X305100Y203450D01*
X304832D01*
X304563Y203553D01*
X304333Y203708D01*
X304142Y203915D01*
G01X302728Y204742D02*
X302460Y205103D01*
X302230Y205310D01*
X301923Y205413D01*
X301655Y205310D01*
X301463Y205103D01*
X301310Y204793D01*
X301272Y204432D01*
X301310Y204122D01*
X301463Y203812D01*
X301693Y203553D01*
X301962Y203450D01*
X302268Y203553D01*
X302537Y203863D01*
X302690Y204328D01*
X302728Y204845D01*
X302652Y205517D01*
X302537Y205878D01*
X302345Y206240D01*
X302077Y206498D01*
X301808Y206550D01*
X301540Y206447D01*
X301348Y206188D01*
G01X299628Y204742D02*
X299360Y205103D01*
X299130Y205310D01*
X298823Y205413D01*
X298555Y205310D01*
X298363Y205103D01*
X298210Y204793D01*
X298172Y204432D01*
X298210Y204122D01*
X298363Y203812D01*
X298593Y203553D01*
X298862Y203450D01*
X299168Y203553D01*
X299437Y203863D01*
X299590Y204328D01*
X299628Y204845D01*
X299552Y205517D01*
X299437Y205878D01*
X299245Y206240D01*
X298977Y206498D01*
X298708Y206550D01*
X298440Y206447D01*
X298248Y206188D01*
G01X299967Y216450D02*
X300019Y216143D01*
X300225Y215875D01*
X300535Y215645D01*
X300897Y215492D01*
X301310Y215415D01*
X301724D01*
X302137Y215492D01*
X302499Y215645D01*
X302809Y215875D01*
X303015Y216143D01*
X303067Y216450D01*
X303015Y216757D01*
X302809Y217025D01*
X302499Y217255D01*
X302137Y217408D01*
X301724Y217485D01*
X301310D01*
X300897Y217408D01*
X300535Y217255D01*
X300225Y217025D01*
X300019Y216757D01*
X299967Y216450D01*
G01X300794Y216757D02*
X299967Y217217D01*
G01X302550Y218822D02*
X302860Y219052D01*
X303015Y219320D01*
X303067Y219627D01*
X302964Y220010D01*
X302705Y220278D01*
X302395Y220355D01*
X302085Y220317D01*
X301827Y220163D01*
X301310Y219397D01*
X300949Y219052D01*
X300432Y218822D01*
X299967Y218745D01*
Y220355D01*
G01X299950Y229950D02*
X300002Y229643D01*
X300208Y229375D01*
X300518Y229145D01*
X300880Y228992D01*
X301293Y228915D01*
X301707D01*
X302120Y228992D01*
X302482Y229145D01*
X302792Y229375D01*
X302998Y229643D01*
X303050Y229950D01*
X302998Y230257D01*
X302792Y230525D01*
X302482Y230755D01*
X302120Y230908D01*
X301707Y230985D01*
X301293D01*
X300880Y230908D01*
X300518Y230755D01*
X300208Y230525D01*
X300002Y230257D01*
X299950Y229950D01*
G01X300777Y230257D02*
X299950Y230717D01*
G01X300570Y232207D02*
X300208Y232437D01*
X300002Y232743D01*
X299950Y233088D01*
X300002Y233395D01*
X300260Y233702D01*
X300570Y233893D01*
X300880Y233932D01*
X301242Y233855D01*
X301500Y233587D01*
X301603Y233318D01*
Y232973D01*
G01Y233318D02*
X301758Y233548D01*
X302017Y233740D01*
X302327Y233817D01*
X302637Y233740D01*
X302895Y233548D01*
X303050Y233203D01*
X302998Y232858D01*
X302792Y232513D01*
G01X295228Y237533D02*
X294998Y237843D01*
X294730Y237998D01*
X294423Y238050D01*
X294040Y237947D01*
X293772Y237688D01*
X293695Y237378D01*
X293733Y237068D01*
X293887Y236810D01*
X294653Y236293D01*
X294998Y235932D01*
X295228Y235415D01*
X295305Y234950D01*
X293695D01*
G01X297292Y285743D02*
X297447Y285513D01*
X297550Y285245D01*
Y284938D01*
X297395Y284593D01*
X297137Y284325D01*
X296827Y284133D01*
X296310Y283980D01*
X295845Y283942D01*
X295380Y284018D01*
X295070Y284133D01*
X294760Y284363D01*
X294553Y284632D01*
X294450Y284900D01*
Y285168D01*
X294553Y285437D01*
X294708Y285667D01*
X294915Y285858D01*
G01Y287157D02*
X294657Y287387D01*
X294502Y287655D01*
X294450Y288000D01*
X294553Y288345D01*
X294760Y288613D01*
X295122Y288805D01*
X295535Y288843D01*
X295948Y288767D01*
X296207Y288575D01*
X296413Y288307D01*
X296465Y288038D01*
X296413Y287770D01*
X296207Y287425D01*
X297550Y287540D01*
Y288575D01*
G01X294450Y291100D02*
X294502Y291368D01*
X294657Y291675D01*
X294915Y291867D01*
X295277Y291943D01*
X295638Y291867D01*
X295948Y291637D01*
X296103Y291292D01*
Y290908D01*
X296207Y290678D01*
X296465Y290487D01*
X296827Y290410D01*
X297188Y290525D01*
X297447Y290793D01*
X297550Y291100D01*
X297447Y291407D01*
X297188Y291675D01*
X296827Y291790D01*
X296465Y291713D01*
X296207Y291522D01*
X296103Y291292D01*
Y290908D01*
X295948Y290563D01*
X295638Y290333D01*
X295277Y290257D01*
X294915Y290333D01*
X294657Y290525D01*
X294502Y290832D01*
X294450Y291100D01*
G01X304792Y284193D02*
X304947Y283963D01*
X305050Y283695D01*
Y283388D01*
X304895Y283043D01*
X304637Y282775D01*
X304327Y282583D01*
X303810Y282430D01*
X303345Y282392D01*
X302880Y282468D01*
X302570Y282583D01*
X302260Y282813D01*
X302053Y283082D01*
X301950Y283350D01*
Y283618D01*
X302053Y283887D01*
X302208Y284117D01*
X302415Y284308D01*
G01X304533Y285722D02*
X304843Y285952D01*
X304998Y286220D01*
X305050Y286527D01*
X304947Y286910D01*
X304688Y287178D01*
X304378Y287255D01*
X304068Y287217D01*
X303810Y287063D01*
X303293Y286297D01*
X302932Y285952D01*
X302415Y285722D01*
X301950Y285645D01*
Y287255D01*
G01Y289550D02*
X302002Y289818D01*
X302157Y290125D01*
X302415Y290317D01*
X302777Y290393D01*
X303138Y290317D01*
X303448Y290087D01*
X303603Y289742D01*
Y289358D01*
X303707Y289128D01*
X303965Y288937D01*
X304327Y288860D01*
X304688Y288975D01*
X304947Y289243D01*
X305050Y289550D01*
X304947Y289857D01*
X304688Y290125D01*
X304327Y290240D01*
X303965Y290163D01*
X303707Y289972D01*
X303603Y289742D01*
Y289358D01*
X303448Y289013D01*
X303138Y288783D01*
X302777Y288707D01*
X302415Y288783D01*
X302157Y288975D01*
X302002Y289282D01*
X301950Y289550D01*
G01X304533Y291922D02*
X304843Y292152D01*
X304998Y292420D01*
X305050Y292727D01*
X304947Y293110D01*
X304688Y293378D01*
X304378Y293455D01*
X304068Y293417D01*
X303810Y293263D01*
X303293Y292497D01*
X302932Y292152D01*
X302415Y291922D01*
X301950Y291845D01*
Y293455D01*
G01X308567Y319966D02*
Y323066D01*
X307608D01*
X307302Y322911D01*
X307110Y322704D01*
X307033Y322291D01*
X307110Y321878D01*
X307340Y321619D01*
X307608Y321464D01*
X308567D01*
G01X307608D02*
X307033Y319966D01*
G01X305428Y321258D02*
X305160Y321619D01*
X304930Y321826D01*
X304623Y321929D01*
X304355Y321826D01*
X304163Y321619D01*
X304010Y321309D01*
X303972Y320948D01*
X304010Y320638D01*
X304163Y320328D01*
X304393Y320069D01*
X304662Y319966D01*
X304968Y320069D01*
X305237Y320379D01*
X305390Y320844D01*
X305428Y321361D01*
X305352Y322033D01*
X305237Y322394D01*
X305045Y322756D01*
X304777Y323014D01*
X304508Y323066D01*
X304240Y322963D01*
X304048Y322704D01*
G01X301600Y319966D02*
Y323066D01*
X302060Y322446D01*
G01Y319966D02*
X301140D01*
G01X310117Y328950D02*
Y332050D01*
X309158D01*
X308852Y331895D01*
X308660Y331688D01*
X308583Y331275D01*
X308660Y330862D01*
X308890Y330603D01*
X309158Y330448D01*
X310117D01*
G01X309158D02*
X308583Y328950D01*
G01X306250D02*
Y332050D01*
X306710Y331430D01*
G01Y328950D02*
X305790D01*
G01X303993Y329415D02*
X303763Y329157D01*
X303495Y329002D01*
X303150Y328950D01*
X302805Y329053D01*
X302537Y329260D01*
X302345Y329622D01*
X302307Y330035D01*
X302383Y330448D01*
X302575Y330707D01*
X302843Y330913D01*
X303112Y330965D01*
X303380Y330913D01*
X303725Y330707D01*
X303610Y332050D01*
X302575D01*
G01X299590Y328950D02*
Y332050D01*
X301008Y329828D01*
X299092D01*
G01X310117Y333450D02*
Y336550D01*
X309158D01*
X308852Y336395D01*
X308660Y336188D01*
X308583Y335775D01*
X308660Y335362D01*
X308890Y335103D01*
X309158Y334948D01*
X310117D01*
G01X309158D02*
X308583Y333450D01*
G01X306250D02*
Y336550D01*
X306710Y335930D01*
G01Y333450D02*
X305790D01*
G01X303993Y333915D02*
X303763Y333657D01*
X303495Y333502D01*
X303150Y333450D01*
X302805Y333553D01*
X302537Y333760D01*
X302345Y334122D01*
X302307Y334535D01*
X302383Y334948D01*
X302575Y335207D01*
X302843Y335413D01*
X303112Y335465D01*
X303380Y335413D01*
X303725Y335207D01*
X303610Y336550D01*
X302575D01*
G01X300050Y333450D02*
Y336550D01*
X300510Y335930D01*
G01Y333450D02*
X299590D01*
G01X308567Y324966D02*
Y328066D01*
X307608D01*
X307302Y327911D01*
X307110Y327704D01*
X307033Y327291D01*
X307110Y326878D01*
X307340Y326619D01*
X307608Y326464D01*
X308567D01*
G01X307608D02*
X307033Y324966D01*
G01X305428Y326258D02*
X305160Y326619D01*
X304930Y326826D01*
X304623Y326929D01*
X304355Y326826D01*
X304163Y326619D01*
X304010Y326309D01*
X303972Y325948D01*
X304010Y325638D01*
X304163Y325328D01*
X304393Y325069D01*
X304662Y324966D01*
X304968Y325069D01*
X305237Y325379D01*
X305390Y325844D01*
X305428Y326361D01*
X305352Y327033D01*
X305237Y327394D01*
X305045Y327756D01*
X304777Y328014D01*
X304508Y328066D01*
X304240Y327963D01*
X304048Y327704D01*
G01X302328Y327549D02*
X302098Y327859D01*
X301830Y328014D01*
X301523Y328066D01*
X301140Y327963D01*
X300872Y327704D01*
X300795Y327394D01*
X300833Y327084D01*
X300987Y326826D01*
X301753Y326309D01*
X302098Y325948D01*
X302328Y325431D01*
X302405Y324966D01*
X300795D01*
G01X311728Y215033D02*
X311498Y215343D01*
X311230Y215498D01*
X310923Y215550D01*
X310540Y215447D01*
X310272Y215188D01*
X310195Y214878D01*
X310233Y214568D01*
X310387Y214310D01*
X311153Y213793D01*
X311498Y213432D01*
X311728Y212915D01*
X311805Y212450D01*
X310195D01*
G01X325792Y285743D02*
X325947Y285513D01*
X326050Y285245D01*
Y284938D01*
X325895Y284593D01*
X325637Y284325D01*
X325327Y284133D01*
X324810Y283980D01*
X324345Y283942D01*
X323880Y284018D01*
X323570Y284133D01*
X323260Y284363D01*
X323053Y284632D01*
X322950Y284900D01*
Y285168D01*
X323053Y285437D01*
X323208Y285667D01*
X323415Y285858D01*
G01X324242Y287272D02*
X324603Y287540D01*
X324810Y287770D01*
X324913Y288077D01*
X324810Y288345D01*
X324603Y288537D01*
X324293Y288690D01*
X323932Y288728D01*
X323622Y288690D01*
X323312Y288537D01*
X323053Y288307D01*
X322950Y288038D01*
X323053Y287732D01*
X323363Y287463D01*
X323828Y287310D01*
X324345Y287272D01*
X325017Y287348D01*
X325378Y287463D01*
X325740Y287655D01*
X325998Y287923D01*
X326050Y288192D01*
X325947Y288460D01*
X325688Y288652D01*
G01X325533Y290372D02*
X325843Y290602D01*
X325998Y290870D01*
X326050Y291177D01*
X325947Y291560D01*
X325688Y291828D01*
X325378Y291905D01*
X325068Y291867D01*
X324810Y291713D01*
X324293Y290947D01*
X323932Y290602D01*
X323415Y290372D01*
X322950Y290295D01*
Y291905D01*
G01X312292Y284193D02*
X312447Y283963D01*
X312550Y283695D01*
Y283388D01*
X312395Y283043D01*
X312137Y282775D01*
X311827Y282583D01*
X311310Y282430D01*
X310845Y282392D01*
X310380Y282468D01*
X310070Y282583D01*
X309760Y282813D01*
X309553Y283082D01*
X309450Y283350D01*
Y283618D01*
X309553Y283887D01*
X309708Y284117D01*
X309915Y284308D01*
G01X312033Y285722D02*
X312343Y285952D01*
X312498Y286220D01*
X312550Y286527D01*
X312447Y286910D01*
X312188Y287178D01*
X311878Y287255D01*
X311568Y287217D01*
X311310Y287063D01*
X310793Y286297D01*
X310432Y285952D01*
X309915Y285722D01*
X309450Y285645D01*
Y287255D01*
G01Y289550D02*
X309502Y289818D01*
X309657Y290125D01*
X309915Y290317D01*
X310277Y290393D01*
X310638Y290317D01*
X310948Y290087D01*
X311103Y289742D01*
Y289358D01*
X311207Y289128D01*
X311465Y288937D01*
X311827Y288860D01*
X312188Y288975D01*
X312447Y289243D01*
X312550Y289550D01*
X312447Y289857D01*
X312188Y290125D01*
X311827Y290240D01*
X311465Y290163D01*
X311207Y289972D01*
X311103Y289742D01*
Y289358D01*
X310948Y289013D01*
X310638Y288783D01*
X310277Y288707D01*
X309915Y288783D01*
X309657Y288975D01*
X309502Y289282D01*
X309450Y289550D01*
G01X310070Y291807D02*
X309708Y292037D01*
X309502Y292343D01*
X309450Y292688D01*
X309502Y292995D01*
X309760Y293302D01*
X310070Y293493D01*
X310380Y293532D01*
X310742Y293455D01*
X311000Y293187D01*
X311103Y292918D01*
Y292573D01*
G01Y292918D02*
X311258Y293148D01*
X311517Y293340D01*
X311827Y293417D01*
X312137Y293340D01*
X312395Y293148D01*
X312550Y292803D01*
X312498Y292458D01*
X312292Y292113D01*
G01X320133Y284352D02*
X317033D01*
Y285886D01*
G01X317653Y287376D02*
X317291Y287606D01*
X317085Y287912D01*
X317033Y288257D01*
X317085Y288564D01*
X317343Y288871D01*
X317653Y289062D01*
X317963Y289101D01*
X318325Y289024D01*
X318583Y288756D01*
X318686Y288487D01*
Y288142D01*
G01Y288487D02*
X318841Y288717D01*
X319100Y288909D01*
X319410Y288986D01*
X319720Y288909D01*
X319978Y288717D01*
X320133Y288372D01*
X320081Y288027D01*
X319875Y287682D01*
G01X333117Y318950D02*
Y322050D01*
X332158D01*
X331852Y321895D01*
X331660Y321688D01*
X331583Y321275D01*
X331660Y320862D01*
X331890Y320603D01*
X332158Y320448D01*
X333117D01*
G01X332158D02*
X331583Y318950D01*
G01X329250D02*
Y322050D01*
X329710Y321430D01*
G01Y318950D02*
X328790D01*
G01X325690D02*
Y322050D01*
X327108Y319828D01*
X325192D01*
G01X323702Y319312D02*
X323433Y319053D01*
X323127Y318950D01*
X322820Y319053D01*
X322552Y319363D01*
X322360Y319828D01*
X322283Y320293D01*
Y320862D01*
X322360Y321327D01*
X322552Y321740D01*
X322782Y321947D01*
X323050Y322050D01*
X323357Y321947D01*
X323587Y321740D01*
X323740Y321430D01*
X323817Y321017D01*
X323740Y320655D01*
X323548Y320293D01*
X323318Y320087D01*
X323050Y320035D01*
X322743Y320138D01*
X322513Y320397D01*
X322283Y320862D01*
G01X333117Y327950D02*
Y331050D01*
X332158D01*
X331852Y330895D01*
X331660Y330688D01*
X331583Y330275D01*
X331660Y329862D01*
X331890Y329603D01*
X332158Y329448D01*
X333117D01*
G01X332158D02*
X331583Y327950D01*
G01X329250D02*
Y331050D01*
X329710Y330430D01*
G01Y327950D02*
X328790D01*
G01X326993Y328415D02*
X326763Y328157D01*
X326495Y328002D01*
X326150Y327950D01*
X325805Y328053D01*
X325537Y328260D01*
X325345Y328622D01*
X325307Y329035D01*
X325383Y329448D01*
X325575Y329707D01*
X325843Y329913D01*
X326112Y329965D01*
X326380Y329913D01*
X326725Y329707D01*
X326610Y331050D01*
X325575D01*
G01X323893Y328570D02*
X323663Y328208D01*
X323357Y328002D01*
X323012Y327950D01*
X322705Y328002D01*
X322398Y328260D01*
X322207Y328570D01*
X322168Y328880D01*
X322245Y329242D01*
X322513Y329500D01*
X322782Y329603D01*
X323127D01*
G01X322782D02*
X322552Y329758D01*
X322360Y330017D01*
X322283Y330327D01*
X322360Y330637D01*
X322552Y330895D01*
X322897Y331050D01*
X323242Y330998D01*
X323587Y330792D01*
G01X333117Y332450D02*
Y335550D01*
X332158D01*
X331852Y335395D01*
X331660Y335188D01*
X331583Y334775D01*
X331660Y334362D01*
X331890Y334103D01*
X332158Y333948D01*
X333117D01*
G01X332158D02*
X331583Y332450D01*
G01X329250D02*
Y335550D01*
X329710Y334930D01*
G01Y332450D02*
X328790D01*
G01X326993Y332915D02*
X326763Y332657D01*
X326495Y332502D01*
X326150Y332450D01*
X325805Y332553D01*
X325537Y332760D01*
X325345Y333122D01*
X325307Y333535D01*
X325383Y333948D01*
X325575Y334207D01*
X325843Y334413D01*
X326112Y334465D01*
X326380Y334413D01*
X326725Y334207D01*
X326610Y335550D01*
X325575D01*
G01X323050D02*
X323357Y335447D01*
X323587Y335188D01*
X323740Y334878D01*
X323855Y334465D01*
X323893Y334000D01*
X323855Y333535D01*
X323740Y333122D01*
X323587Y332812D01*
X323357Y332553D01*
X323050Y332450D01*
X322743Y332553D01*
X322513Y332812D01*
X322360Y333122D01*
X322245Y333535D01*
X322207Y334000D01*
X322245Y334465D01*
X322360Y334878D01*
X322513Y335188D01*
X322743Y335447D01*
X323050Y335550D01*
G01X333117Y336950D02*
Y340050D01*
X332158D01*
X331852Y339895D01*
X331660Y339688D01*
X331583Y339275D01*
X331660Y338862D01*
X331890Y338603D01*
X332158Y338448D01*
X333117D01*
G01X332158D02*
X331583Y336950D01*
G01X329250D02*
Y340050D01*
X329710Y339430D01*
G01Y336950D02*
X328790D01*
G01X325690D02*
Y340050D01*
X327108Y337828D01*
X325192D01*
G01X323778Y338242D02*
X323510Y338603D01*
X323280Y338810D01*
X322973Y338913D01*
X322705Y338810D01*
X322513Y338603D01*
X322360Y338293D01*
X322322Y337932D01*
X322360Y337622D01*
X322513Y337312D01*
X322743Y337053D01*
X323012Y336950D01*
X323318Y337053D01*
X323587Y337363D01*
X323740Y337828D01*
X323778Y338345D01*
X323702Y339017D01*
X323587Y339378D01*
X323395Y339740D01*
X323127Y339998D01*
X322858Y340050D01*
X322590Y339947D01*
X322398Y339688D01*
G01X333117Y323450D02*
Y326550D01*
X332158D01*
X331852Y326395D01*
X331660Y326188D01*
X331583Y325775D01*
X331660Y325362D01*
X331890Y325103D01*
X332158Y324948D01*
X333117D01*
G01X332158D02*
X331583Y323450D01*
G01X329250D02*
Y326550D01*
X329710Y325930D01*
G01Y323450D02*
X328790D01*
G01X326993Y323915D02*
X326763Y323657D01*
X326495Y323502D01*
X326150Y323450D01*
X325805Y323553D01*
X325537Y323760D01*
X325345Y324122D01*
X325307Y324535D01*
X325383Y324948D01*
X325575Y325207D01*
X325843Y325413D01*
X326112Y325465D01*
X326380Y325413D01*
X326725Y325207D01*
X326610Y326550D01*
X325575D01*
G01X323778Y326033D02*
X323548Y326343D01*
X323280Y326498D01*
X322973Y326550D01*
X322590Y326447D01*
X322322Y326188D01*
X322245Y325878D01*
X322283Y325568D01*
X322437Y325310D01*
X323203Y324793D01*
X323548Y324432D01*
X323778Y323915D01*
X323855Y323450D01*
X322245D01*
G01X331567Y345950D02*
Y349050D01*
X330608D01*
X330302Y348895D01*
X330110Y348688D01*
X330033Y348275D01*
X330110Y347862D01*
X330340Y347603D01*
X330608Y347448D01*
X331567D01*
G01X330608D02*
X330033Y345950D01*
G01X328428Y347242D02*
X328160Y347603D01*
X327930Y347810D01*
X327623Y347913D01*
X327355Y347810D01*
X327163Y347603D01*
X327010Y347293D01*
X326972Y346932D01*
X327010Y346622D01*
X327163Y346312D01*
X327393Y346053D01*
X327662Y345950D01*
X327968Y346053D01*
X328237Y346363D01*
X328390Y346828D01*
X328428Y347345D01*
X328352Y348017D01*
X328237Y348378D01*
X328045Y348740D01*
X327777Y348998D01*
X327508Y349050D01*
X327240Y348947D01*
X327048Y348688D01*
G01X324600Y349050D02*
X324907Y348947D01*
X325137Y348688D01*
X325290Y348378D01*
X325405Y347965D01*
X325443Y347500D01*
X325405Y347035D01*
X325290Y346622D01*
X325137Y346312D01*
X324907Y346053D01*
X324600Y345950D01*
X324293Y346053D01*
X324063Y346312D01*
X323910Y346622D01*
X323795Y347035D01*
X323757Y347500D01*
X323795Y347965D01*
X323910Y348378D01*
X324063Y348688D01*
X324293Y348947D01*
X324600Y349050D01*
G01X333117Y341450D02*
Y344550D01*
X332158D01*
X331852Y344395D01*
X331660Y344188D01*
X331583Y343775D01*
X331660Y343362D01*
X331890Y343103D01*
X332158Y342948D01*
X333117D01*
G01X332158D02*
X331583Y341450D01*
G01X329250D02*
Y344550D01*
X329710Y343930D01*
G01Y341450D02*
X328790D01*
G01X326993Y341915D02*
X326763Y341657D01*
X326495Y341502D01*
X326150Y341450D01*
X325805Y341553D01*
X325537Y341760D01*
X325345Y342122D01*
X325307Y342535D01*
X325383Y342948D01*
X325575Y343207D01*
X325843Y343413D01*
X326112Y343465D01*
X326380Y343413D01*
X326725Y343207D01*
X326610Y344550D01*
X325575D01*
G01X323893Y341915D02*
X323663Y341657D01*
X323395Y341502D01*
X323050Y341450D01*
X322705Y341553D01*
X322437Y341760D01*
X322245Y342122D01*
X322207Y342535D01*
X322283Y342948D01*
X322475Y343207D01*
X322743Y343413D01*
X323012Y343465D01*
X323280Y343413D01*
X323625Y343207D01*
X323510Y344550D01*
X322475D01*
G01X319792Y387743D02*
X319947Y387513D01*
X320050Y387245D01*
Y386938D01*
X319895Y386593D01*
X319637Y386325D01*
X319327Y386133D01*
X318810Y385980D01*
X318345Y385942D01*
X317880Y386018D01*
X317570Y386133D01*
X317260Y386363D01*
X317053Y386632D01*
X316950Y386900D01*
Y387168D01*
X317053Y387437D01*
X317208Y387667D01*
X317415Y387858D01*
G01Y389157D02*
X317157Y389387D01*
X317002Y389655D01*
X316950Y390000D01*
X317053Y390345D01*
X317260Y390613D01*
X317622Y390805D01*
X318035Y390843D01*
X318448Y390767D01*
X318707Y390575D01*
X318913Y390307D01*
X318965Y390038D01*
X318913Y389770D01*
X318707Y389425D01*
X320050Y389540D01*
Y390575D01*
G01X316950Y393023D02*
X317622Y393100D01*
X318190Y393215D01*
X318707Y393368D01*
X319275Y393560D01*
X320050Y393867D01*
Y392333D01*
G01X316950Y375133D02*
X320050D01*
Y376092D01*
X319895Y376398D01*
X319688Y376590D01*
X319275Y376667D01*
X318862Y376590D01*
X318603Y376360D01*
X318448Y376092D01*
Y375133D01*
G01Y376092D02*
X316950Y376667D01*
G01X317570Y378157D02*
X317208Y378387D01*
X317002Y378693D01*
X316950Y379038D01*
X317002Y379345D01*
X317260Y379652D01*
X317570Y379843D01*
X317880Y379882D01*
X318242Y379805D01*
X318500Y379537D01*
X318603Y379268D01*
Y378923D01*
G01Y379268D02*
X318758Y379498D01*
X319017Y379690D01*
X319327Y379767D01*
X319637Y379690D01*
X319895Y379498D01*
X320050Y379153D01*
X319998Y378808D01*
X319792Y378463D01*
G01X317312Y381448D02*
X317053Y381717D01*
X316950Y382023D01*
X317053Y382330D01*
X317363Y382598D01*
X317828Y382790D01*
X318293Y382867D01*
X318862D01*
X319327Y382790D01*
X319740Y382598D01*
X319947Y382368D01*
X320050Y382100D01*
X319947Y381793D01*
X319740Y381563D01*
X319430Y381410D01*
X319017Y381333D01*
X318655Y381410D01*
X318293Y381602D01*
X318087Y381832D01*
X318035Y382100D01*
X318138Y382407D01*
X318397Y382637D01*
X318862Y382867D01*
G01X328757Y408292D02*
X328987Y408447D01*
X329255Y408550D01*
X329562D01*
X329907Y408395D01*
X330175Y408137D01*
X330367Y407827D01*
X330520Y407310D01*
X330558Y406845D01*
X330482Y406380D01*
X330367Y406070D01*
X330137Y405760D01*
X329868Y405553D01*
X329600Y405450D01*
X329332D01*
X329063Y405553D01*
X328833Y405708D01*
X328642Y405915D01*
G01X327343D02*
X327113Y405657D01*
X326845Y405502D01*
X326500Y405450D01*
X326155Y405553D01*
X325887Y405760D01*
X325695Y406122D01*
X325657Y406535D01*
X325733Y406948D01*
X325925Y407207D01*
X326193Y407413D01*
X326462Y407465D01*
X326730Y407413D01*
X327075Y407207D01*
X326960Y408550D01*
X325925D01*
G01X324128Y406742D02*
X323860Y407103D01*
X323630Y407310D01*
X323323Y407413D01*
X323055Y407310D01*
X322863Y407103D01*
X322710Y406793D01*
X322672Y406432D01*
X322710Y406122D01*
X322863Y405812D01*
X323093Y405553D01*
X323362Y405450D01*
X323668Y405553D01*
X323937Y405863D01*
X324090Y406328D01*
X324128Y406845D01*
X324052Y407517D01*
X323937Y407878D01*
X323745Y408240D01*
X323477Y408498D01*
X323208Y408550D01*
X322940Y408447D01*
X322748Y408188D01*
G01X348367Y223950D02*
Y227050D01*
X347408D01*
X347102Y226895D01*
X346910Y226688D01*
X346833Y226275D01*
X346910Y225862D01*
X347140Y225603D01*
X347408Y225448D01*
X348367D01*
G01X347408D02*
X346833Y223950D01*
G01X344577D02*
X344500Y224622D01*
X344385Y225190D01*
X344232Y225707D01*
X344040Y226275D01*
X343733Y227050D01*
X345267D01*
G01X340940Y223950D02*
Y227050D01*
X342358Y224828D01*
X340442D01*
G01X337867Y223950D02*
Y227050D01*
X336908D01*
X336602Y226895D01*
X336410Y226688D01*
X336333Y226275D01*
X336410Y225862D01*
X336640Y225603D01*
X336908Y225448D01*
X337867D01*
G01X336908D02*
X336333Y223950D01*
G01X334077D02*
X334000Y224622D01*
X333885Y225190D01*
X333732Y225707D01*
X333540Y226275D01*
X333233Y227050D01*
X334767D01*
G01X331743Y224415D02*
X331513Y224157D01*
X331245Y224002D01*
X330900Y223950D01*
X330555Y224053D01*
X330287Y224260D01*
X330095Y224622D01*
X330057Y225035D01*
X330133Y225448D01*
X330325Y225707D01*
X330593Y225913D01*
X330862Y225965D01*
X331130Y225913D01*
X331475Y225707D01*
X331360Y227050D01*
X330325D01*
G01X337867Y219450D02*
Y222550D01*
X336908D01*
X336602Y222395D01*
X336410Y222188D01*
X336333Y221775D01*
X336410Y221362D01*
X336640Y221103D01*
X336908Y220948D01*
X337867D01*
G01X336908D02*
X336333Y219450D01*
G01X334077D02*
X334000Y220122D01*
X333885Y220690D01*
X333732Y221207D01*
X333540Y221775D01*
X333233Y222550D01*
X334767D01*
G01X330977Y219450D02*
X330900Y220122D01*
X330785Y220690D01*
X330632Y221207D01*
X330440Y221775D01*
X330133Y222550D01*
X331667D01*
G01X348367Y219450D02*
Y222550D01*
X347408D01*
X347102Y222395D01*
X346910Y222188D01*
X346833Y221775D01*
X346910Y221362D01*
X347140Y221103D01*
X347408Y220948D01*
X348367D01*
G01X347408D02*
X346833Y219450D01*
G01X344577D02*
X344500Y220122D01*
X344385Y220690D01*
X344232Y221207D01*
X344040Y221775D01*
X343733Y222550D01*
X345267D01*
G01X342128Y220742D02*
X341860Y221103D01*
X341630Y221310D01*
X341323Y221413D01*
X341055Y221310D01*
X340863Y221103D01*
X340710Y220793D01*
X340672Y220432D01*
X340710Y220122D01*
X340863Y219812D01*
X341093Y219553D01*
X341362Y219450D01*
X341668Y219553D01*
X341937Y219863D01*
X342090Y220328D01*
X342128Y220845D01*
X342052Y221517D01*
X341937Y221878D01*
X341745Y222240D01*
X341477Y222498D01*
X341208Y222550D01*
X340940Y222447D01*
X340748Y222188D01*
G01X331950Y249333D02*
X335050D01*
Y250292D01*
X334895Y250598D01*
X334688Y250790D01*
X334275Y250867D01*
X333862Y250790D01*
X333603Y250560D01*
X333448Y250292D01*
Y249333D01*
G01Y250292D02*
X331950Y250867D01*
G01Y253200D02*
X332002Y253468D01*
X332157Y253775D01*
X332415Y253967D01*
X332777Y254043D01*
X333138Y253967D01*
X333448Y253737D01*
X333603Y253392D01*
Y253008D01*
X333707Y252778D01*
X333965Y252587D01*
X334327Y252510D01*
X334688Y252625D01*
X334947Y252893D01*
X335050Y253200D01*
X334947Y253507D01*
X334688Y253775D01*
X334327Y253890D01*
X333965Y253813D01*
X333707Y253622D01*
X333603Y253392D01*
Y253008D01*
X333448Y252663D01*
X333138Y252433D01*
X332777Y252357D01*
X332415Y252433D01*
X332157Y252625D01*
X332002Y252932D01*
X331950Y253200D01*
G01X335050Y256300D02*
X334947Y255993D01*
X334688Y255763D01*
X334378Y255610D01*
X333965Y255495D01*
X333500Y255457D01*
X333035Y255495D01*
X332622Y255610D01*
X332312Y255763D01*
X332053Y255993D01*
X331950Y256300D01*
X332053Y256607D01*
X332312Y256837D01*
X332622Y256990D01*
X333035Y257105D01*
X333500Y257143D01*
X333965Y257105D01*
X334378Y256990D01*
X334688Y256837D01*
X334947Y256607D01*
X335050Y256300D01*
G01X333450Y283083D02*
X336550D01*
Y284042D01*
X336395Y284348D01*
X336188Y284540D01*
X335775Y284617D01*
X335362Y284540D01*
X335103Y284310D01*
X334948Y284042D01*
Y283083D01*
G01Y284042D02*
X333450Y284617D01*
G01X334070Y286107D02*
X333708Y286337D01*
X333502Y286643D01*
X333450Y286988D01*
X333502Y287295D01*
X333760Y287602D01*
X334070Y287793D01*
X334380Y287832D01*
X334742Y287755D01*
X335000Y287487D01*
X335103Y287218D01*
Y286873D01*
G01Y287218D02*
X335258Y287448D01*
X335517Y287640D01*
X335827Y287717D01*
X336137Y287640D01*
X336395Y287448D01*
X336550Y287103D01*
X336498Y286758D01*
X336292Y286413D01*
G01X334742Y289322D02*
X335103Y289590D01*
X335310Y289820D01*
X335413Y290127D01*
X335310Y290395D01*
X335103Y290587D01*
X334793Y290740D01*
X334432Y290778D01*
X334122Y290740D01*
X333812Y290587D01*
X333553Y290357D01*
X333450Y290088D01*
X333553Y289782D01*
X333863Y289513D01*
X334328Y289360D01*
X334845Y289322D01*
X335517Y289398D01*
X335878Y289513D01*
X336240Y289705D01*
X336498Y289973D01*
X336550Y290242D01*
X336447Y290510D01*
X336188Y290702D01*
G01X334070Y292307D02*
X333708Y292537D01*
X333502Y292843D01*
X333450Y293188D01*
X333502Y293495D01*
X333760Y293802D01*
X334070Y293993D01*
X334380Y294032D01*
X334742Y293955D01*
X335000Y293687D01*
X335103Y293418D01*
Y293073D01*
G01Y293418D02*
X335258Y293648D01*
X335517Y293840D01*
X335827Y293917D01*
X336137Y293840D01*
X336395Y293648D01*
X336550Y293303D01*
X336498Y292958D01*
X336292Y292613D01*
G01X337950Y283083D02*
X341050D01*
Y284042D01*
X340895Y284348D01*
X340688Y284540D01*
X340275Y284617D01*
X339862Y284540D01*
X339603Y284310D01*
X339448Y284042D01*
Y283083D01*
G01Y284042D02*
X337950Y284617D01*
G01X338570Y286107D02*
X338208Y286337D01*
X338002Y286643D01*
X337950Y286988D01*
X338002Y287295D01*
X338260Y287602D01*
X338570Y287793D01*
X338880Y287832D01*
X339242Y287755D01*
X339500Y287487D01*
X339603Y287218D01*
Y286873D01*
G01Y287218D02*
X339758Y287448D01*
X340017Y287640D01*
X340327Y287717D01*
X340637Y287640D01*
X340895Y287448D01*
X341050Y287103D01*
X340998Y286758D01*
X340792Y286413D01*
G01X337950Y290510D02*
X341050D01*
X338828Y289092D01*
Y291008D01*
G01X340533Y292422D02*
X340843Y292652D01*
X340998Y292920D01*
X341050Y293227D01*
X340947Y293610D01*
X340688Y293878D01*
X340378Y293955D01*
X340068Y293917D01*
X339810Y293763D01*
X339293Y292997D01*
X338932Y292652D01*
X338415Y292422D01*
X337950Y292345D01*
Y293955D01*
G01X340367Y408466D02*
Y411566D01*
X339408D01*
X339102Y411411D01*
X338910Y411204D01*
X338833Y410791D01*
X338910Y410378D01*
X339140Y410119D01*
X339408Y409964D01*
X340367D01*
G01X339408D02*
X338833Y408466D01*
G01X337343Y409086D02*
X337113Y408724D01*
X336807Y408518D01*
X336462Y408466D01*
X336155Y408518D01*
X335848Y408776D01*
X335657Y409086D01*
X335618Y409396D01*
X335695Y409758D01*
X335963Y410016D01*
X336232Y410119D01*
X336577D01*
G01X336232D02*
X336002Y410274D01*
X335810Y410533D01*
X335733Y410843D01*
X335810Y411153D01*
X336002Y411411D01*
X336347Y411566D01*
X336692Y411514D01*
X337037Y411308D01*
G01X333477Y408466D02*
X333400Y409138D01*
X333285Y409706D01*
X333132Y410223D01*
X332940Y410791D01*
X332633Y411566D01*
X334167D01*
G01X340705Y393563D02*
X340398Y393305D01*
X340053Y393150D01*
X339747D01*
X339440Y393305D01*
X339210Y393563D01*
X339095Y393925D01*
X339172Y394287D01*
X339363Y394597D01*
X339708Y394803D01*
X340168Y394907D01*
X340437Y395113D01*
X340552Y395475D01*
X340475Y395837D01*
X340283Y396095D01*
X340015Y396250D01*
X339747D01*
X339478Y396147D01*
X339248Y395888D01*
G01X337567Y393150D02*
Y396250D01*
X336647D01*
X336340Y396095D01*
X336110Y395733D01*
X336033Y395320D01*
X336110Y394907D01*
X336302Y394597D01*
X336647Y394442D01*
X337567D01*
G01X334428Y395733D02*
X334198Y396043D01*
X333930Y396198D01*
X333623Y396250D01*
X333240Y396147D01*
X332972Y395888D01*
X332895Y395578D01*
X332933Y395268D01*
X333087Y395010D01*
X333853Y394493D01*
X334198Y394132D01*
X334428Y393615D01*
X334505Y393150D01*
X332895D01*
G01X347292Y130693D02*
X347447Y130463D01*
X347550Y130195D01*
Y129888D01*
X347395Y129543D01*
X347137Y129275D01*
X346827Y129083D01*
X346310Y128930D01*
X345845Y128892D01*
X345380Y128968D01*
X345070Y129083D01*
X344760Y129313D01*
X344553Y129582D01*
X344450Y129850D01*
Y130118D01*
X344553Y130387D01*
X344708Y130617D01*
X344915Y130808D01*
G01X344450Y132950D02*
X347550D01*
X346930Y132490D01*
G01X344450D02*
Y133410D01*
G01Y136510D02*
X347550D01*
X345328Y135092D01*
Y137008D01*
G01X345070Y138307D02*
X344708Y138537D01*
X344502Y138843D01*
X344450Y139188D01*
X344502Y139495D01*
X344760Y139802D01*
X345070Y139993D01*
X345380Y140032D01*
X345742Y139955D01*
X346000Y139687D01*
X346103Y139418D01*
Y139073D01*
G01Y139418D02*
X346258Y139648D01*
X346517Y139840D01*
X346827Y139917D01*
X347137Y139840D01*
X347395Y139648D01*
X347550Y139303D01*
X347498Y138958D01*
X347292Y138613D01*
G01X353292Y131693D02*
X353447Y131463D01*
X353550Y131195D01*
Y130888D01*
X353395Y130543D01*
X353137Y130275D01*
X352827Y130083D01*
X352310Y129930D01*
X351845Y129892D01*
X351380Y129968D01*
X351070Y130083D01*
X350760Y130313D01*
X350553Y130582D01*
X350450Y130850D01*
Y131118D01*
X350553Y131387D01*
X350708Y131617D01*
X350915Y131808D01*
G01X350450Y133950D02*
X353550D01*
X352930Y133490D01*
G01X350450D02*
Y134410D01*
G01X351070Y136207D02*
X350708Y136437D01*
X350502Y136743D01*
X350450Y137088D01*
X350502Y137395D01*
X350760Y137702D01*
X351070Y137893D01*
X351380Y137932D01*
X351742Y137855D01*
X352000Y137587D01*
X352103Y137318D01*
Y136973D01*
G01Y137318D02*
X352258Y137548D01*
X352517Y137740D01*
X352827Y137817D01*
X353137Y137740D01*
X353395Y137548D01*
X353550Y137203D01*
X353498Y136858D01*
X353292Y136513D01*
G01X351742Y139422D02*
X352103Y139690D01*
X352310Y139920D01*
X352413Y140227D01*
X352310Y140495D01*
X352103Y140687D01*
X351793Y140840D01*
X351432Y140878D01*
X351122Y140840D01*
X350812Y140687D01*
X350553Y140457D01*
X350450Y140188D01*
X350553Y139882D01*
X350863Y139613D01*
X351328Y139460D01*
X351845Y139422D01*
X352517Y139498D01*
X352878Y139613D01*
X353240Y139805D01*
X353498Y140073D01*
X353550Y140342D01*
X353447Y140610D01*
X353188Y140802D01*
G01X351792Y178743D02*
X351947Y178513D01*
X352050Y178245D01*
Y177938D01*
X351895Y177593D01*
X351637Y177325D01*
X351327Y177133D01*
X350810Y176980D01*
X350345Y176942D01*
X349880Y177018D01*
X349570Y177133D01*
X349260Y177363D01*
X349053Y177632D01*
X348950Y177900D01*
Y178168D01*
X349053Y178437D01*
X349208Y178667D01*
X349415Y178858D01*
G01X350242Y180272D02*
X350603Y180540D01*
X350810Y180770D01*
X350913Y181077D01*
X350810Y181345D01*
X350603Y181537D01*
X350293Y181690D01*
X349932Y181728D01*
X349622Y181690D01*
X349312Y181537D01*
X349053Y181307D01*
X348950Y181038D01*
X349053Y180732D01*
X349363Y180463D01*
X349828Y180310D01*
X350345Y180272D01*
X351017Y180348D01*
X351378Y180463D01*
X351740Y180655D01*
X351998Y180923D01*
X352050Y181192D01*
X351947Y181460D01*
X351688Y181652D01*
G01X348950Y184023D02*
X349622Y184100D01*
X350190Y184215D01*
X350707Y184368D01*
X351275Y184560D01*
X352050Y184867D01*
Y183333D01*
G01X360817Y191599D02*
Y194699D01*
X359858D01*
X359552Y194544D01*
X359360Y194337D01*
X359283Y193924D01*
X359360Y193511D01*
X359590Y193252D01*
X359858Y193097D01*
X360817D01*
G01X359858D02*
X359283Y191599D01*
G01X356950D02*
Y194699D01*
X357410Y194079D01*
G01Y191599D02*
X356490D01*
G01X353850Y194699D02*
X354157Y194596D01*
X354387Y194337D01*
X354540Y194027D01*
X354655Y193614D01*
X354693Y193149D01*
X354655Y192684D01*
X354540Y192271D01*
X354387Y191961D01*
X354157Y191702D01*
X353850Y191599D01*
X353543Y191702D01*
X353313Y191961D01*
X353160Y192271D01*
X353045Y192684D01*
X353007Y193149D01*
X353045Y193614D01*
X353160Y194027D01*
X353313Y194337D01*
X353543Y194596D01*
X353850Y194699D01*
G01X351593Y192064D02*
X351363Y191806D01*
X351095Y191651D01*
X350750Y191599D01*
X350405Y191702D01*
X350137Y191909D01*
X349945Y192271D01*
X349907Y192684D01*
X349983Y193097D01*
X350175Y193356D01*
X350443Y193562D01*
X350712Y193614D01*
X350980Y193562D01*
X351325Y193356D01*
X351210Y194699D01*
X350175D01*
G01X360817Y187099D02*
Y190199D01*
X359858D01*
X359552Y190044D01*
X359360Y189837D01*
X359283Y189424D01*
X359360Y189011D01*
X359590Y188752D01*
X359858Y188597D01*
X360817D01*
G01X359858D02*
X359283Y187099D01*
G01X356950D02*
Y190199D01*
X357410Y189579D01*
G01Y187099D02*
X356490D01*
G01X353850Y190199D02*
X354157Y190096D01*
X354387Y189837D01*
X354540Y189527D01*
X354655Y189114D01*
X354693Y188649D01*
X354655Y188184D01*
X354540Y187771D01*
X354387Y187461D01*
X354157Y187202D01*
X353850Y187099D01*
X353543Y187202D01*
X353313Y187461D01*
X353160Y187771D01*
X353045Y188184D01*
X353007Y188649D01*
X353045Y189114D01*
X353160Y189527D01*
X353313Y189837D01*
X353543Y190096D01*
X353850Y190199D01*
G01X351478Y188391D02*
X351210Y188752D01*
X350980Y188959D01*
X350673Y189062D01*
X350405Y188959D01*
X350213Y188752D01*
X350060Y188442D01*
X350022Y188081D01*
X350060Y187771D01*
X350213Y187461D01*
X350443Y187202D01*
X350712Y187099D01*
X351018Y187202D01*
X351287Y187512D01*
X351440Y187977D01*
X351478Y188494D01*
X351402Y189166D01*
X351287Y189527D01*
X351095Y189889D01*
X350827Y190147D01*
X350558Y190199D01*
X350290Y190096D01*
X350098Y189837D01*
G01X366807Y218292D02*
X367037Y218447D01*
X367305Y218550D01*
X367612D01*
X367957Y218395D01*
X368225Y218137D01*
X368417Y217827D01*
X368570Y217310D01*
X368608Y216845D01*
X368532Y216380D01*
X368417Y216070D01*
X368187Y215760D01*
X367918Y215553D01*
X367650Y215450D01*
X367382D01*
X367113Y215553D01*
X366883Y215708D01*
X366692Y215915D01*
G01X364550Y215450D02*
Y218550D01*
X365010Y217930D01*
G01Y215450D02*
X364090D01*
G01X362293Y215915D02*
X362063Y215657D01*
X361795Y215502D01*
X361450Y215450D01*
X361105Y215553D01*
X360837Y215760D01*
X360645Y216122D01*
X360607Y216535D01*
X360683Y216948D01*
X360875Y217207D01*
X361143Y217413D01*
X361412Y217465D01*
X361680Y217413D01*
X362025Y217207D01*
X361910Y218550D01*
X360875D01*
G01X358350D02*
X358657Y218447D01*
X358887Y218188D01*
X359040Y217878D01*
X359155Y217465D01*
X359193Y217000D01*
X359155Y216535D01*
X359040Y216122D01*
X358887Y215812D01*
X358657Y215553D01*
X358350Y215450D01*
X358043Y215553D01*
X357813Y215812D01*
X357660Y216122D01*
X357545Y216535D01*
X357507Y217000D01*
X357545Y217465D01*
X357660Y217878D01*
X357813Y218188D01*
X358043Y218447D01*
X358350Y218550D01*
G01X368307Y224292D02*
X368537Y224447D01*
X368805Y224550D01*
X369112D01*
X369457Y224395D01*
X369725Y224137D01*
X369917Y223827D01*
X370070Y223310D01*
X370108Y222845D01*
X370032Y222380D01*
X369917Y222070D01*
X369687Y221760D01*
X369418Y221553D01*
X369150Y221450D01*
X368882D01*
X368613Y221553D01*
X368383Y221708D01*
X368192Y221915D01*
G01X366050Y221450D02*
Y224550D01*
X366510Y223930D01*
G01Y221450D02*
X365590D01*
G01X363793Y221915D02*
X363563Y221657D01*
X363295Y221502D01*
X362950Y221450D01*
X362605Y221553D01*
X362337Y221760D01*
X362145Y222122D01*
X362107Y222535D01*
X362183Y222948D01*
X362375Y223207D01*
X362643Y223413D01*
X362912Y223465D01*
X363180Y223413D01*
X363525Y223207D01*
X363410Y224550D01*
X362375D01*
G01X359850Y221450D02*
X359582Y221502D01*
X359275Y221657D01*
X359083Y221915D01*
X359007Y222277D01*
X359083Y222638D01*
X359313Y222948D01*
X359658Y223103D01*
X360042D01*
X360272Y223207D01*
X360463Y223465D01*
X360540Y223827D01*
X360425Y224188D01*
X360157Y224447D01*
X359850Y224550D01*
X359543Y224447D01*
X359275Y224188D01*
X359160Y223827D01*
X359237Y223465D01*
X359428Y223207D01*
X359658Y223103D01*
X360042D01*
X360387Y222948D01*
X360617Y222638D01*
X360693Y222277D01*
X360617Y221915D01*
X360425Y221657D01*
X360118Y221502D01*
X359850Y221450D01*
G01X345450Y230083D02*
X348550D01*
Y231042D01*
X348395Y231348D01*
X348188Y231540D01*
X347775Y231617D01*
X347362Y231540D01*
X347103Y231310D01*
X346948Y231042D01*
Y230083D01*
G01Y231042D02*
X345450Y231617D01*
G01Y233950D02*
X348550D01*
X347930Y233490D01*
G01X345450D02*
Y234410D01*
G01X346742Y236322D02*
X347103Y236590D01*
X347310Y236820D01*
X347413Y237127D01*
X347310Y237395D01*
X347103Y237587D01*
X346793Y237740D01*
X346432Y237778D01*
X346122Y237740D01*
X345812Y237587D01*
X345553Y237357D01*
X345450Y237088D01*
X345553Y236782D01*
X345863Y236513D01*
X346328Y236360D01*
X346845Y236322D01*
X347517Y236398D01*
X347878Y236513D01*
X348240Y236705D01*
X348498Y236973D01*
X348550Y237242D01*
X348447Y237510D01*
X348188Y237702D01*
G01X345450Y240150D02*
X345502Y240418D01*
X345657Y240725D01*
X345915Y240917D01*
X346277Y240993D01*
X346638Y240917D01*
X346948Y240687D01*
X347103Y240342D01*
Y239958D01*
X347207Y239728D01*
X347465Y239537D01*
X347827Y239460D01*
X348188Y239575D01*
X348447Y239843D01*
X348550Y240150D01*
X348447Y240457D01*
X348188Y240725D01*
X347827Y240840D01*
X347465Y240763D01*
X347207Y240572D01*
X347103Y240342D01*
Y239958D01*
X346948Y239613D01*
X346638Y239383D01*
X346277Y239307D01*
X345915Y239383D01*
X345657Y239575D01*
X345502Y239882D01*
X345450Y240150D01*
G01X342450Y283083D02*
X345550D01*
Y284042D01*
X345395Y284348D01*
X345188Y284540D01*
X344775Y284617D01*
X344362Y284540D01*
X344103Y284310D01*
X343948Y284042D01*
Y283083D01*
G01Y284042D02*
X342450Y284617D01*
G01X343070Y286107D02*
X342708Y286337D01*
X342502Y286643D01*
X342450Y286988D01*
X342502Y287295D01*
X342760Y287602D01*
X343070Y287793D01*
X343380Y287832D01*
X343742Y287755D01*
X344000Y287487D01*
X344103Y287218D01*
Y286873D01*
G01Y287218D02*
X344258Y287448D01*
X344517Y287640D01*
X344827Y287717D01*
X345137Y287640D01*
X345395Y287448D01*
X345550Y287103D01*
X345498Y286758D01*
X345292Y286413D01*
G01X343070Y289207D02*
X342708Y289437D01*
X342502Y289743D01*
X342450Y290088D01*
X342502Y290395D01*
X342760Y290702D01*
X343070Y290893D01*
X343380Y290932D01*
X343742Y290855D01*
X344000Y290587D01*
X344103Y290318D01*
Y289973D01*
G01Y290318D02*
X344258Y290548D01*
X344517Y290740D01*
X344827Y290817D01*
X345137Y290740D01*
X345395Y290548D01*
X345550Y290203D01*
X345498Y289858D01*
X345292Y289513D01*
G01X345550Y293150D02*
X345447Y292843D01*
X345188Y292613D01*
X344878Y292460D01*
X344465Y292345D01*
X344000Y292307D01*
X343535Y292345D01*
X343122Y292460D01*
X342812Y292613D01*
X342553Y292843D01*
X342450Y293150D01*
X342553Y293457D01*
X342812Y293687D01*
X343122Y293840D01*
X343535Y293955D01*
X344000Y293993D01*
X344465Y293955D01*
X344878Y293840D01*
X345188Y293687D01*
X345447Y293457D01*
X345550Y293150D01*
G01X346950Y283083D02*
X350050D01*
Y284042D01*
X349895Y284348D01*
X349688Y284540D01*
X349275Y284617D01*
X348862Y284540D01*
X348603Y284310D01*
X348448Y284042D01*
Y283083D01*
G01Y284042D02*
X346950Y284617D01*
G01X347570Y286107D02*
X347208Y286337D01*
X347002Y286643D01*
X346950Y286988D01*
X347002Y287295D01*
X347260Y287602D01*
X347570Y287793D01*
X347880Y287832D01*
X348242Y287755D01*
X348500Y287487D01*
X348603Y287218D01*
Y286873D01*
G01Y287218D02*
X348758Y287448D01*
X349017Y287640D01*
X349327Y287717D01*
X349637Y287640D01*
X349895Y287448D01*
X350050Y287103D01*
X349998Y286758D01*
X349792Y286413D01*
G01X346950Y290510D02*
X350050D01*
X347828Y289092D01*
Y291008D01*
G01X346950Y293150D02*
X350050D01*
X349430Y292690D01*
G01X346950D02*
Y293610D01*
G01X353917Y335450D02*
Y338550D01*
X352958D01*
X352652Y338395D01*
X352460Y338188D01*
X352383Y337775D01*
X352460Y337362D01*
X352690Y337103D01*
X352958Y336948D01*
X353917D01*
G01X352958D02*
X352383Y335450D01*
G01X350050D02*
Y338550D01*
X350510Y337930D01*
G01Y335450D02*
X349590D01*
G01X347602Y335812D02*
X347333Y335553D01*
X347027Y335450D01*
X346720Y335553D01*
X346452Y335863D01*
X346260Y336328D01*
X346183Y336793D01*
Y337362D01*
X346260Y337827D01*
X346452Y338240D01*
X346682Y338447D01*
X346950Y338550D01*
X347257Y338447D01*
X347487Y338240D01*
X347640Y337930D01*
X347717Y337517D01*
X347640Y337155D01*
X347448Y336793D01*
X347218Y336587D01*
X346950Y336535D01*
X346643Y336638D01*
X346413Y336897D01*
X346183Y337362D01*
G01X344502Y335812D02*
X344233Y335553D01*
X343927Y335450D01*
X343620Y335553D01*
X343352Y335863D01*
X343160Y336328D01*
X343083Y336793D01*
Y337362D01*
X343160Y337827D01*
X343352Y338240D01*
X343582Y338447D01*
X343850Y338550D01*
X344157Y338447D01*
X344387Y338240D01*
X344540Y337930D01*
X344617Y337517D01*
X344540Y337155D01*
X344348Y336793D01*
X344118Y336587D01*
X343850Y336535D01*
X343543Y336638D01*
X343313Y336897D01*
X343083Y337362D01*
G01X353917Y330950D02*
Y334050D01*
X352958D01*
X352652Y333895D01*
X352460Y333688D01*
X352383Y333275D01*
X352460Y332862D01*
X352690Y332603D01*
X352958Y332448D01*
X353917D01*
G01X352958D02*
X352383Y330950D01*
G01X350050D02*
Y334050D01*
X350510Y333430D01*
G01Y330950D02*
X349590D01*
G01X347602Y331312D02*
X347333Y331053D01*
X347027Y330950D01*
X346720Y331053D01*
X346452Y331363D01*
X346260Y331828D01*
X346183Y332293D01*
Y332862D01*
X346260Y333327D01*
X346452Y333740D01*
X346682Y333947D01*
X346950Y334050D01*
X347257Y333947D01*
X347487Y333740D01*
X347640Y333430D01*
X347717Y333017D01*
X347640Y332655D01*
X347448Y332293D01*
X347218Y332087D01*
X346950Y332035D01*
X346643Y332138D01*
X346413Y332397D01*
X346183Y332862D01*
G01X344578Y333533D02*
X344348Y333843D01*
X344080Y333998D01*
X343773Y334050D01*
X343390Y333947D01*
X343122Y333688D01*
X343045Y333378D01*
X343083Y333068D01*
X343237Y332810D01*
X344003Y332293D01*
X344348Y331932D01*
X344578Y331415D01*
X344655Y330950D01*
X343045D01*
G01X353917Y326450D02*
Y329550D01*
X352958D01*
X352652Y329395D01*
X352460Y329188D01*
X352383Y328775D01*
X352460Y328362D01*
X352690Y328103D01*
X352958Y327948D01*
X353917D01*
G01X352958D02*
X352383Y326450D01*
G01X350778Y329033D02*
X350548Y329343D01*
X350280Y329498D01*
X349973Y329550D01*
X349590Y329447D01*
X349322Y329188D01*
X349245Y328878D01*
X349283Y328568D01*
X349437Y328310D01*
X350203Y327793D01*
X350548Y327432D01*
X350778Y326915D01*
X350855Y326450D01*
X349245D01*
G01X346950Y329550D02*
X347257Y329447D01*
X347487Y329188D01*
X347640Y328878D01*
X347755Y328465D01*
X347793Y328000D01*
X347755Y327535D01*
X347640Y327122D01*
X347487Y326812D01*
X347257Y326553D01*
X346950Y326450D01*
X346643Y326553D01*
X346413Y326812D01*
X346260Y327122D01*
X346145Y327535D01*
X346107Y328000D01*
X346145Y328465D01*
X346260Y328878D01*
X346413Y329188D01*
X346643Y329447D01*
X346950Y329550D01*
G01X344578Y329033D02*
X344348Y329343D01*
X344080Y329498D01*
X343773Y329550D01*
X343390Y329447D01*
X343122Y329188D01*
X343045Y328878D01*
X343083Y328568D01*
X343237Y328310D01*
X344003Y327793D01*
X344348Y327432D01*
X344578Y326915D01*
X344655Y326450D01*
X343045D01*
G01X353917Y321950D02*
Y325050D01*
X352958D01*
X352652Y324895D01*
X352460Y324688D01*
X352383Y324275D01*
X352460Y323862D01*
X352690Y323603D01*
X352958Y323448D01*
X353917D01*
G01X352958D02*
X352383Y321950D01*
G01X350778Y324533D02*
X350548Y324843D01*
X350280Y324998D01*
X349973Y325050D01*
X349590Y324947D01*
X349322Y324688D01*
X349245Y324378D01*
X349283Y324068D01*
X349437Y323810D01*
X350203Y323293D01*
X350548Y322932D01*
X350778Y322415D01*
X350855Y321950D01*
X349245D01*
G01X346950Y325050D02*
X347257Y324947D01*
X347487Y324688D01*
X347640Y324378D01*
X347755Y323965D01*
X347793Y323500D01*
X347755Y323035D01*
X347640Y322622D01*
X347487Y322312D01*
X347257Y322053D01*
X346950Y321950D01*
X346643Y322053D01*
X346413Y322312D01*
X346260Y322622D01*
X346145Y323035D01*
X346107Y323500D01*
X346145Y323965D01*
X346260Y324378D01*
X346413Y324688D01*
X346643Y324947D01*
X346950Y325050D01*
G01X344578Y323242D02*
X344310Y323603D01*
X344080Y323810D01*
X343773Y323913D01*
X343505Y323810D01*
X343313Y323603D01*
X343160Y323293D01*
X343122Y322932D01*
X343160Y322622D01*
X343313Y322312D01*
X343543Y322053D01*
X343812Y321950D01*
X344118Y322053D01*
X344387Y322363D01*
X344540Y322828D01*
X344578Y323345D01*
X344502Y324017D01*
X344387Y324378D01*
X344195Y324740D01*
X343927Y324998D01*
X343658Y325050D01*
X343390Y324947D01*
X343198Y324688D01*
G01X353917Y339950D02*
Y343050D01*
X352958D01*
X352652Y342895D01*
X352460Y342688D01*
X352383Y342275D01*
X352460Y341862D01*
X352690Y341603D01*
X352958Y341448D01*
X353917D01*
G01X352958D02*
X352383Y339950D01*
G01X350778Y342533D02*
X350548Y342843D01*
X350280Y342998D01*
X349973Y343050D01*
X349590Y342947D01*
X349322Y342688D01*
X349245Y342378D01*
X349283Y342068D01*
X349437Y341810D01*
X350203Y341293D01*
X350548Y340932D01*
X350778Y340415D01*
X350855Y339950D01*
X349245D01*
G01X346950Y343050D02*
X347257Y342947D01*
X347487Y342688D01*
X347640Y342378D01*
X347755Y341965D01*
X347793Y341500D01*
X347755Y341035D01*
X347640Y340622D01*
X347487Y340312D01*
X347257Y340053D01*
X346950Y339950D01*
X346643Y340053D01*
X346413Y340312D01*
X346260Y340622D01*
X346145Y341035D01*
X346107Y341500D01*
X346145Y341965D01*
X346260Y342378D01*
X346413Y342688D01*
X346643Y342947D01*
X346950Y343050D01*
G01X344693Y340570D02*
X344463Y340208D01*
X344157Y340002D01*
X343812Y339950D01*
X343505Y340002D01*
X343198Y340260D01*
X343007Y340570D01*
X342968Y340880D01*
X343045Y341242D01*
X343313Y341500D01*
X343582Y341603D01*
X343927D01*
G01X343582D02*
X343352Y341758D01*
X343160Y342017D01*
X343083Y342327D01*
X343160Y342637D01*
X343352Y342895D01*
X343697Y343050D01*
X344042Y342998D01*
X344387Y342792D01*
G01X358167Y387150D02*
Y390250D01*
X357208D01*
X356902Y390095D01*
X356710Y389888D01*
X356633Y389475D01*
X356710Y389062D01*
X356940Y388803D01*
X357208Y388648D01*
X358167D01*
G01X357208D02*
X356633Y387150D01*
G01X355143Y387615D02*
X354913Y387357D01*
X354645Y387202D01*
X354300Y387150D01*
X353955Y387253D01*
X353687Y387460D01*
X353495Y387822D01*
X353457Y388235D01*
X353533Y388648D01*
X353725Y388907D01*
X353993Y389113D01*
X354262Y389165D01*
X354530Y389113D01*
X354875Y388907D01*
X354760Y390250D01*
X353725D01*
G01X350740Y387150D02*
Y390250D01*
X352158Y388028D01*
X350242D01*
G01X356557Y395492D02*
X356787Y395647D01*
X357055Y395750D01*
X357362D01*
X357707Y395595D01*
X357975Y395337D01*
X358167Y395027D01*
X358320Y394510D01*
X358358Y394045D01*
X358282Y393580D01*
X358167Y393270D01*
X357937Y392960D01*
X357668Y392753D01*
X357400Y392650D01*
X357132D01*
X356863Y392753D01*
X356633Y392908D01*
X356442Y393115D01*
G01X355143D02*
X354913Y392857D01*
X354645Y392702D01*
X354300Y392650D01*
X353955Y392753D01*
X353687Y392960D01*
X353495Y393322D01*
X353457Y393735D01*
X353533Y394148D01*
X353725Y394407D01*
X353993Y394613D01*
X354262Y394665D01*
X354530Y394613D01*
X354875Y394407D01*
X354760Y395750D01*
X353725D01*
G01X350740Y392650D02*
Y395750D01*
X352158Y393528D01*
X350242D01*
G01X358107Y404492D02*
X358337Y404647D01*
X358605Y404750D01*
X358912D01*
X359257Y404595D01*
X359525Y404337D01*
X359717Y404027D01*
X359870Y403510D01*
X359908Y403045D01*
X359832Y402580D01*
X359717Y402270D01*
X359487Y401960D01*
X359218Y401753D01*
X358950Y401650D01*
X358682D01*
X358413Y401753D01*
X358183Y401908D01*
X357992Y402115D01*
G01X356578Y404233D02*
X356348Y404543D01*
X356080Y404698D01*
X355773Y404750D01*
X355390Y404647D01*
X355122Y404388D01*
X355045Y404078D01*
X355083Y403768D01*
X355237Y403510D01*
X356003Y402993D01*
X356348Y402632D01*
X356578Y402115D01*
X356655Y401650D01*
X355045D01*
G01X352750D02*
X352482Y401702D01*
X352175Y401857D01*
X351983Y402115D01*
X351907Y402477D01*
X351983Y402838D01*
X352213Y403148D01*
X352558Y403303D01*
X352942D01*
X353172Y403407D01*
X353363Y403665D01*
X353440Y404027D01*
X353325Y404388D01*
X353057Y404647D01*
X352750Y404750D01*
X352443Y404647D01*
X352175Y404388D01*
X352060Y404027D01*
X352137Y403665D01*
X352328Y403407D01*
X352558Y403303D01*
X352942D01*
X353287Y403148D01*
X353517Y402838D01*
X353593Y402477D01*
X353517Y402115D01*
X353325Y401857D01*
X353018Y401702D01*
X352750Y401650D01*
G01X350378Y402942D02*
X350110Y403303D01*
X349880Y403510D01*
X349573Y403613D01*
X349305Y403510D01*
X349113Y403303D01*
X348960Y402993D01*
X348922Y402632D01*
X348960Y402322D01*
X349113Y402012D01*
X349343Y401753D01*
X349612Y401650D01*
X349918Y401753D01*
X350187Y402063D01*
X350340Y402528D01*
X350378Y403045D01*
X350302Y403717D01*
X350187Y404078D01*
X349995Y404440D01*
X349727Y404698D01*
X349458Y404750D01*
X349190Y404647D01*
X348998Y404388D01*
G01X358167Y406150D02*
Y409250D01*
X357208D01*
X356902Y409095D01*
X356710Y408888D01*
X356633Y408475D01*
X356710Y408062D01*
X356940Y407803D01*
X357208Y407648D01*
X358167D01*
G01X357208D02*
X356633Y406150D01*
G01X355143Y406615D02*
X354913Y406357D01*
X354645Y406202D01*
X354300Y406150D01*
X353955Y406253D01*
X353687Y406460D01*
X353495Y406822D01*
X353457Y407235D01*
X353533Y407648D01*
X353725Y407907D01*
X353993Y408113D01*
X354262Y408165D01*
X354530Y408113D01*
X354875Y407907D01*
X354760Y409250D01*
X353725D01*
G01X352043Y406770D02*
X351813Y406408D01*
X351507Y406202D01*
X351162Y406150D01*
X350855Y406202D01*
X350548Y406460D01*
X350357Y406770D01*
X350318Y407080D01*
X350395Y407442D01*
X350663Y407700D01*
X350932Y407803D01*
X351277D01*
G01X350932D02*
X350702Y407958D01*
X350510Y408217D01*
X350433Y408527D01*
X350510Y408837D01*
X350702Y409095D01*
X351047Y409250D01*
X351392Y409198D01*
X351737Y408992D01*
G01X358167Y397150D02*
Y400250D01*
X357208D01*
X356902Y400095D01*
X356710Y399888D01*
X356633Y399475D01*
X356710Y399062D01*
X356940Y398803D01*
X357208Y398648D01*
X358167D01*
G01X357208D02*
X356633Y397150D01*
G01X355143Y397770D02*
X354913Y397408D01*
X354607Y397202D01*
X354262Y397150D01*
X353955Y397202D01*
X353648Y397460D01*
X353457Y397770D01*
X353418Y398080D01*
X353495Y398442D01*
X353763Y398700D01*
X354032Y398803D01*
X354377D01*
G01X354032D02*
X353802Y398958D01*
X353610Y399217D01*
X353533Y399527D01*
X353610Y399837D01*
X353802Y400095D01*
X354147Y400250D01*
X354492Y400198D01*
X354837Y399992D01*
G01X351928Y398442D02*
X351660Y398803D01*
X351430Y399010D01*
X351123Y399113D01*
X350855Y399010D01*
X350663Y398803D01*
X350510Y398493D01*
X350472Y398132D01*
X350510Y397822D01*
X350663Y397512D01*
X350893Y397253D01*
X351162Y397150D01*
X351468Y397253D01*
X351737Y397563D01*
X351890Y398028D01*
X351928Y398545D01*
X351852Y399217D01*
X351737Y399578D01*
X351545Y399940D01*
X351277Y400198D01*
X351008Y400250D01*
X350740Y400147D01*
X350548Y399888D01*
G01X362717Y419182D02*
Y422282D01*
X361758D01*
X361452Y422127D01*
X361260Y421920D01*
X361183Y421507D01*
X361260Y421094D01*
X361490Y420835D01*
X361758Y420680D01*
X362717D01*
G01X361758D02*
X361183Y419182D01*
G01X359578Y421765D02*
X359348Y422075D01*
X359080Y422230D01*
X358773Y422282D01*
X358390Y422179D01*
X358122Y421920D01*
X358045Y421610D01*
X358083Y421300D01*
X358237Y421042D01*
X359003Y420525D01*
X359348Y420164D01*
X359578Y419647D01*
X359655Y419182D01*
X358045D01*
G01X356478Y420474D02*
X356210Y420835D01*
X355980Y421042D01*
X355673Y421145D01*
X355405Y421042D01*
X355213Y420835D01*
X355060Y420525D01*
X355022Y420164D01*
X355060Y419854D01*
X355213Y419544D01*
X355443Y419285D01*
X355712Y419182D01*
X356018Y419285D01*
X356287Y419595D01*
X356440Y420060D01*
X356478Y420577D01*
X356402Y421249D01*
X356287Y421610D01*
X356095Y421972D01*
X355827Y422230D01*
X355558Y422282D01*
X355290Y422179D01*
X355098Y421920D01*
G01X353493Y419802D02*
X353263Y419440D01*
X352957Y419234D01*
X352612Y419182D01*
X352305Y419234D01*
X351998Y419492D01*
X351807Y419802D01*
X351768Y420112D01*
X351845Y420474D01*
X352113Y420732D01*
X352382Y420835D01*
X352727D01*
G01X352382D02*
X352152Y420990D01*
X351960Y421249D01*
X351883Y421559D01*
X351960Y421869D01*
X352152Y422127D01*
X352497Y422282D01*
X352842Y422230D01*
X353187Y422024D01*
G01X359867Y411966D02*
Y415066D01*
X358908D01*
X358602Y414911D01*
X358410Y414704D01*
X358333Y414291D01*
X358410Y413878D01*
X358640Y413619D01*
X358908Y413464D01*
X359867D01*
G01X358908D02*
X358333Y411966D01*
G01X356843Y412431D02*
X356613Y412173D01*
X356345Y412018D01*
X356000Y411966D01*
X355655Y412069D01*
X355387Y412276D01*
X355195Y412638D01*
X355157Y413051D01*
X355233Y413464D01*
X355425Y413723D01*
X355693Y413929D01*
X355962Y413981D01*
X356230Y413929D01*
X356575Y413723D01*
X356460Y415066D01*
X355425D01*
G01X352900Y411966D02*
Y415066D01*
X353360Y414446D01*
G01Y411966D02*
X352440D01*
G01X378342Y74193D02*
X378497Y73963D01*
X378600Y73695D01*
Y73388D01*
X378445Y73043D01*
X378187Y72775D01*
X377877Y72583D01*
X377360Y72430D01*
X376895Y72392D01*
X376430Y72468D01*
X376120Y72583D01*
X375810Y72813D01*
X375603Y73082D01*
X375500Y73350D01*
Y73618D01*
X375603Y73887D01*
X375758Y74117D01*
X375965Y74308D01*
G01X378083Y75722D02*
X378393Y75952D01*
X378548Y76220D01*
X378600Y76527D01*
X378497Y76910D01*
X378238Y77178D01*
X377928Y77255D01*
X377618Y77217D01*
X377360Y77063D01*
X376843Y76297D01*
X376482Y75952D01*
X375965Y75722D01*
X375500Y75645D01*
Y77255D01*
G01Y80010D02*
X378600D01*
X376378Y78592D01*
Y80508D01*
G01X375965Y81807D02*
X375707Y82037D01*
X375552Y82305D01*
X375500Y82650D01*
X375603Y82995D01*
X375810Y83263D01*
X376172Y83455D01*
X376585Y83493D01*
X376998Y83417D01*
X377257Y83225D01*
X377463Y82957D01*
X377515Y82688D01*
X377463Y82420D01*
X377257Y82075D01*
X378600Y82190D01*
Y83225D01*
G01X379066Y85133D02*
X375966D01*
Y86667D01*
G01Y89000D02*
X379066D01*
X378446Y88540D01*
G01X375966D02*
Y89460D01*
G01X379066Y92100D02*
X378963Y91793D01*
X378704Y91563D01*
X378394Y91410D01*
X377981Y91295D01*
X377516Y91257D01*
X377051Y91295D01*
X376638Y91410D01*
X376328Y91563D01*
X376069Y91793D01*
X375966Y92100D01*
X376069Y92407D01*
X376328Y92637D01*
X376638Y92790D01*
X377051Y92905D01*
X377516Y92943D01*
X377981Y92905D01*
X378394Y92790D01*
X378704Y92637D01*
X378963Y92407D01*
X379066Y92100D01*
G01X380307Y107292D02*
X380537Y107447D01*
X380805Y107550D01*
X381112D01*
X381457Y107395D01*
X381725Y107137D01*
X381917Y106827D01*
X382070Y106310D01*
X382108Y105845D01*
X382032Y105380D01*
X381917Y105070D01*
X381687Y104760D01*
X381418Y104553D01*
X381150Y104450D01*
X380882D01*
X380613Y104553D01*
X380383Y104708D01*
X380192Y104915D01*
G01X378050Y104450D02*
Y107550D01*
X378510Y106930D01*
G01Y104450D02*
X377590D01*
G01X375678Y105742D02*
X375410Y106103D01*
X375180Y106310D01*
X374873Y106413D01*
X374605Y106310D01*
X374413Y106103D01*
X374260Y105793D01*
X374222Y105432D01*
X374260Y105122D01*
X374413Y104812D01*
X374643Y104553D01*
X374912Y104450D01*
X375218Y104553D01*
X375487Y104863D01*
X375640Y105328D01*
X375678Y105845D01*
X375602Y106517D01*
X375487Y106878D01*
X375295Y107240D01*
X375027Y107498D01*
X374758Y107550D01*
X374490Y107447D01*
X374298Y107188D01*
G01X371390Y104450D02*
Y107550D01*
X372808Y105328D01*
X370892D01*
G01X379792Y129693D02*
X379947Y129463D01*
X380050Y129195D01*
Y128888D01*
X379895Y128543D01*
X379637Y128275D01*
X379327Y128083D01*
X378810Y127930D01*
X378345Y127892D01*
X377880Y127968D01*
X377570Y128083D01*
X377260Y128313D01*
X377053Y128582D01*
X376950Y128850D01*
Y129118D01*
X377053Y129387D01*
X377208Y129617D01*
X377415Y129808D01*
G01X376950Y131950D02*
X380050D01*
X379430Y131490D01*
G01X376950D02*
Y132410D01*
G01X379533Y134322D02*
X379843Y134552D01*
X379998Y134820D01*
X380050Y135127D01*
X379947Y135510D01*
X379688Y135778D01*
X379378Y135855D01*
X379068Y135817D01*
X378810Y135663D01*
X378293Y134897D01*
X377932Y134552D01*
X377415Y134322D01*
X376950Y134245D01*
Y135855D01*
G01X377415Y137307D02*
X377157Y137537D01*
X377002Y137805D01*
X376950Y138150D01*
X377053Y138495D01*
X377260Y138763D01*
X377622Y138955D01*
X378035Y138993D01*
X378448Y138917D01*
X378707Y138725D01*
X378913Y138457D01*
X378965Y138188D01*
X378913Y137920D01*
X378707Y137575D01*
X380050Y137690D01*
Y138725D01*
G01X368148Y141133D02*
Y138033D01*
X366614D01*
G01X365124Y138653D02*
X364894Y138291D01*
X364588Y138085D01*
X364243Y138033D01*
X363936Y138085D01*
X363629Y138343D01*
X363438Y138653D01*
X363399Y138963D01*
X363476Y139325D01*
X363744Y139583D01*
X364013Y139686D01*
X364358D01*
G01X364013D02*
X363783Y139841D01*
X363591Y140100D01*
X363514Y140410D01*
X363591Y140720D01*
X363783Y140978D01*
X364128Y141133D01*
X364473Y141081D01*
X364818Y140875D01*
G01X362024Y138498D02*
X361794Y138240D01*
X361526Y138085D01*
X361181Y138033D01*
X360836Y138136D01*
X360568Y138343D01*
X360376Y138705D01*
X360338Y139118D01*
X360414Y139531D01*
X360606Y139790D01*
X360874Y139996D01*
X361143Y140048D01*
X361411Y139996D01*
X361756Y139790D01*
X361641Y141133D01*
X360606D01*
G01X377917Y170450D02*
Y173550D01*
X376958D01*
X376652Y173395D01*
X376460Y173188D01*
X376383Y172775D01*
X376460Y172362D01*
X376690Y172103D01*
X376958Y171948D01*
X377917D01*
G01X376958D02*
X376383Y170450D01*
G01X374050D02*
Y173550D01*
X374510Y172930D01*
G01Y170450D02*
X373590D01*
G01X371602Y170812D02*
X371333Y170553D01*
X371027Y170450D01*
X370720Y170553D01*
X370452Y170863D01*
X370260Y171328D01*
X370183Y171793D01*
Y172362D01*
X370260Y172827D01*
X370452Y173240D01*
X370682Y173447D01*
X370950Y173550D01*
X371257Y173447D01*
X371487Y173240D01*
X371640Y172930D01*
X371717Y172517D01*
X371640Y172155D01*
X371448Y171793D01*
X371218Y171587D01*
X370950Y171535D01*
X370643Y171638D01*
X370413Y171897D01*
X370183Y172362D01*
G01X368578Y171742D02*
X368310Y172103D01*
X368080Y172310D01*
X367773Y172413D01*
X367505Y172310D01*
X367313Y172103D01*
X367160Y171793D01*
X367122Y171432D01*
X367160Y171122D01*
X367313Y170812D01*
X367543Y170553D01*
X367812Y170450D01*
X368118Y170553D01*
X368387Y170863D01*
X368540Y171328D01*
X368578Y171845D01*
X368502Y172517D01*
X368387Y172878D01*
X368195Y173240D01*
X367927Y173498D01*
X367658Y173550D01*
X367390Y173447D01*
X367198Y173188D01*
G01X367492Y294693D02*
X367647Y294463D01*
X367750Y294195D01*
Y293888D01*
X367595Y293543D01*
X367337Y293275D01*
X367027Y293083D01*
X366510Y292930D01*
X366045Y292892D01*
X365580Y292968D01*
X365270Y293083D01*
X364960Y293313D01*
X364753Y293582D01*
X364650Y293850D01*
Y294118D01*
X364753Y294387D01*
X364908Y294617D01*
X365115Y294808D01*
G01X364650Y296950D02*
X367750D01*
X367130Y296490D01*
G01X364650D02*
Y297410D01*
G01Y300050D02*
X364702Y300318D01*
X364857Y300625D01*
X365115Y300817D01*
X365477Y300893D01*
X365838Y300817D01*
X366148Y300587D01*
X366303Y300242D01*
Y299858D01*
X366407Y299628D01*
X366665Y299437D01*
X367027Y299360D01*
X367388Y299475D01*
X367647Y299743D01*
X367750Y300050D01*
X367647Y300357D01*
X367388Y300625D01*
X367027Y300740D01*
X366665Y300663D01*
X366407Y300472D01*
X366303Y300242D01*
Y299858D01*
X366148Y299513D01*
X365838Y299283D01*
X365477Y299207D01*
X365115Y299283D01*
X364857Y299475D01*
X364702Y299782D01*
X364650Y300050D01*
G01X367750Y303150D02*
X367647Y302843D01*
X367388Y302613D01*
X367078Y302460D01*
X366665Y302345D01*
X366200Y302307D01*
X365735Y302345D01*
X365322Y302460D01*
X365012Y302613D01*
X364753Y302843D01*
X364650Y303150D01*
X364753Y303457D01*
X365012Y303687D01*
X365322Y303840D01*
X365735Y303955D01*
X366200Y303993D01*
X366665Y303955D01*
X367078Y303840D01*
X367388Y303687D01*
X367647Y303457D01*
X367750Y303150D01*
G01X384417Y307500D02*
Y310600D01*
X383458D01*
X383152Y310445D01*
X382960Y310238D01*
X382883Y309825D01*
X382960Y309412D01*
X383190Y309153D01*
X383458Y308998D01*
X384417D01*
G01X383458D02*
X382883Y307500D01*
G01X380550D02*
Y310600D01*
X381010Y309980D01*
G01Y307500D02*
X380090D01*
G01X377527D02*
X377450Y308172D01*
X377335Y308740D01*
X377182Y309257D01*
X376990Y309825D01*
X376683Y310600D01*
X378217D01*
G01X374427Y307500D02*
X374350Y308172D01*
X374235Y308740D01*
X374082Y309257D01*
X373890Y309825D01*
X373583Y310600D01*
X375117D01*
G01X381917Y321950D02*
Y325050D01*
X380958D01*
X380652Y324895D01*
X380460Y324688D01*
X380383Y324275D01*
X380460Y323862D01*
X380690Y323603D01*
X380958Y323448D01*
X381917D01*
G01X380958D02*
X380383Y321950D01*
G01X378050D02*
Y325050D01*
X378510Y324430D01*
G01Y321950D02*
X377590D01*
G01X375602Y322312D02*
X375333Y322053D01*
X375027Y321950D01*
X374720Y322053D01*
X374452Y322363D01*
X374260Y322828D01*
X374183Y323293D01*
Y323862D01*
X374260Y324327D01*
X374452Y324740D01*
X374682Y324947D01*
X374950Y325050D01*
X375257Y324947D01*
X375487Y324740D01*
X375640Y324430D01*
X375717Y324017D01*
X375640Y323655D01*
X375448Y323293D01*
X375218Y323087D01*
X374950Y323035D01*
X374643Y323138D01*
X374413Y323397D01*
X374183Y323862D01*
G01X371850Y321950D02*
Y325050D01*
X372310Y324430D01*
G01Y321950D02*
X371390D01*
G01X381917Y326450D02*
Y329550D01*
X380958D01*
X380652Y329395D01*
X380460Y329188D01*
X380383Y328775D01*
X380460Y328362D01*
X380690Y328103D01*
X380958Y327948D01*
X381917D01*
G01X380958D02*
X380383Y326450D01*
G01X378778Y329033D02*
X378548Y329343D01*
X378280Y329498D01*
X377973Y329550D01*
X377590Y329447D01*
X377322Y329188D01*
X377245Y328878D01*
X377283Y328568D01*
X377437Y328310D01*
X378203Y327793D01*
X378548Y327432D01*
X378778Y326915D01*
X378855Y326450D01*
X377245D01*
G01X374950Y329550D02*
X375257Y329447D01*
X375487Y329188D01*
X375640Y328878D01*
X375755Y328465D01*
X375793Y328000D01*
X375755Y327535D01*
X375640Y327122D01*
X375487Y326812D01*
X375257Y326553D01*
X374950Y326450D01*
X374643Y326553D01*
X374413Y326812D01*
X374260Y327122D01*
X374145Y327535D01*
X374107Y328000D01*
X374145Y328465D01*
X374260Y328878D01*
X374413Y329188D01*
X374643Y329447D01*
X374950Y329550D01*
G01X371850D02*
X372157Y329447D01*
X372387Y329188D01*
X372540Y328878D01*
X372655Y328465D01*
X372693Y328000D01*
X372655Y327535D01*
X372540Y327122D01*
X372387Y326812D01*
X372157Y326553D01*
X371850Y326450D01*
X371543Y326553D01*
X371313Y326812D01*
X371160Y327122D01*
X371045Y327535D01*
X371007Y328000D01*
X371045Y328465D01*
X371160Y328878D01*
X371313Y329188D01*
X371543Y329447D01*
X371850Y329550D01*
G01X381917Y330950D02*
Y334050D01*
X380958D01*
X380652Y333895D01*
X380460Y333688D01*
X380383Y333275D01*
X380460Y332862D01*
X380690Y332603D01*
X380958Y332448D01*
X381917D01*
G01X380958D02*
X380383Y330950D01*
G01X378778Y333533D02*
X378548Y333843D01*
X378280Y333998D01*
X377973Y334050D01*
X377590Y333947D01*
X377322Y333688D01*
X377245Y333378D01*
X377283Y333068D01*
X377437Y332810D01*
X378203Y332293D01*
X378548Y331932D01*
X378778Y331415D01*
X378855Y330950D01*
X377245D01*
G01X374950Y334050D02*
X375257Y333947D01*
X375487Y333688D01*
X375640Y333378D01*
X375755Y332965D01*
X375793Y332500D01*
X375755Y332035D01*
X375640Y331622D01*
X375487Y331312D01*
X375257Y331053D01*
X374950Y330950D01*
X374643Y331053D01*
X374413Y331312D01*
X374260Y331622D01*
X374145Y332035D01*
X374107Y332500D01*
X374145Y332965D01*
X374260Y333378D01*
X374413Y333688D01*
X374643Y333947D01*
X374950Y334050D01*
G01X371390Y330950D02*
Y334050D01*
X372808Y331828D01*
X370892D01*
G01X381917Y335450D02*
Y338550D01*
X380958D01*
X380652Y338395D01*
X380460Y338188D01*
X380383Y337775D01*
X380460Y337362D01*
X380690Y337103D01*
X380958Y336948D01*
X381917D01*
G01X380958D02*
X380383Y335450D01*
G01X378778Y338033D02*
X378548Y338343D01*
X378280Y338498D01*
X377973Y338550D01*
X377590Y338447D01*
X377322Y338188D01*
X377245Y337878D01*
X377283Y337568D01*
X377437Y337310D01*
X378203Y336793D01*
X378548Y336432D01*
X378778Y335915D01*
X378855Y335450D01*
X377245D01*
G01X374950Y338550D02*
X375257Y338447D01*
X375487Y338188D01*
X375640Y337878D01*
X375755Y337465D01*
X375793Y337000D01*
X375755Y336535D01*
X375640Y336122D01*
X375487Y335812D01*
X375257Y335553D01*
X374950Y335450D01*
X374643Y335553D01*
X374413Y335812D01*
X374260Y336122D01*
X374145Y336535D01*
X374107Y337000D01*
X374145Y337465D01*
X374260Y337878D01*
X374413Y338188D01*
X374643Y338447D01*
X374950Y338550D01*
G01X371850Y335450D02*
Y338550D01*
X372310Y337930D01*
G01Y335450D02*
X371390D01*
G01X381917Y339950D02*
Y343050D01*
X380958D01*
X380652Y342895D01*
X380460Y342688D01*
X380383Y342275D01*
X380460Y341862D01*
X380690Y341603D01*
X380958Y341448D01*
X381917D01*
G01X380958D02*
X380383Y339950D01*
G01X378778Y342533D02*
X378548Y342843D01*
X378280Y342998D01*
X377973Y343050D01*
X377590Y342947D01*
X377322Y342688D01*
X377245Y342378D01*
X377283Y342068D01*
X377437Y341810D01*
X378203Y341293D01*
X378548Y340932D01*
X378778Y340415D01*
X378855Y339950D01*
X377245D01*
G01X374950Y343050D02*
X375257Y342947D01*
X375487Y342688D01*
X375640Y342378D01*
X375755Y341965D01*
X375793Y341500D01*
X375755Y341035D01*
X375640Y340622D01*
X375487Y340312D01*
X375257Y340053D01*
X374950Y339950D01*
X374643Y340053D01*
X374413Y340312D01*
X374260Y340622D01*
X374145Y341035D01*
X374107Y341500D01*
X374145Y341965D01*
X374260Y342378D01*
X374413Y342688D01*
X374643Y342947D01*
X374950Y343050D01*
G01X372693Y340415D02*
X372463Y340157D01*
X372195Y340002D01*
X371850Y339950D01*
X371505Y340053D01*
X371237Y340260D01*
X371045Y340622D01*
X371007Y341035D01*
X371083Y341448D01*
X371275Y341707D01*
X371543Y341913D01*
X371812Y341965D01*
X372080Y341913D01*
X372425Y341707D01*
X372310Y343050D01*
X371275D01*
G01X393536Y130653D02*
X393766Y130808D01*
X394034Y130911D01*
X394341D01*
X394686Y130756D01*
X394954Y130498D01*
X395146Y130188D01*
X395299Y129671D01*
X395337Y129206D01*
X395261Y128741D01*
X395146Y128431D01*
X394916Y128121D01*
X394647Y127914D01*
X394379Y127811D01*
X394111D01*
X393842Y127914D01*
X393612Y128069D01*
X393421Y128276D01*
G01X391279Y127811D02*
Y130911D01*
X391739Y130291D01*
G01Y127811D02*
X390819D01*
G01X388179D02*
Y130911D01*
X388639Y130291D01*
G01Y127811D02*
X387719D01*
G01X385807Y129103D02*
X385539Y129464D01*
X385309Y129671D01*
X385002Y129774D01*
X384734Y129671D01*
X384542Y129464D01*
X384389Y129154D01*
X384351Y128793D01*
X384389Y128483D01*
X384542Y128173D01*
X384772Y127914D01*
X385041Y127811D01*
X385347Y127914D01*
X385616Y128224D01*
X385769Y128689D01*
X385807Y129206D01*
X385731Y129878D01*
X385616Y130239D01*
X385424Y130601D01*
X385156Y130859D01*
X384887Y130911D01*
X384619Y130808D01*
X384427Y130549D01*
G01X395307Y154342D02*
X395537Y154497D01*
X395805Y154600D01*
X396112D01*
X396457Y154445D01*
X396725Y154187D01*
X396917Y153877D01*
X397070Y153360D01*
X397108Y152895D01*
X397032Y152430D01*
X396917Y152120D01*
X396687Y151810D01*
X396418Y151603D01*
X396150Y151500D01*
X395882D01*
X395613Y151603D01*
X395383Y151758D01*
X395192Y151965D01*
G01X393050Y151500D02*
Y154600D01*
X393510Y153980D01*
G01Y151500D02*
X392590D01*
G01X389950D02*
Y154600D01*
X390410Y153980D01*
G01Y151500D02*
X389490D01*
G01X386927D02*
X386850Y152172D01*
X386735Y152740D01*
X386582Y153257D01*
X386390Y153825D01*
X386083Y154600D01*
X387617D01*
G01X392307Y150342D02*
X392537Y150497D01*
X392805Y150600D01*
X393112D01*
X393457Y150445D01*
X393725Y150187D01*
X393917Y149877D01*
X394070Y149360D01*
X394108Y148895D01*
X394032Y148430D01*
X393917Y148120D01*
X393687Y147810D01*
X393418Y147603D01*
X393150Y147500D01*
X392882D01*
X392613Y147603D01*
X392383Y147758D01*
X392192Y147965D01*
G01X390050Y147500D02*
Y150600D01*
X390510Y149980D01*
G01Y147500D02*
X389590D01*
G01X386950D02*
Y150600D01*
X387410Y149980D01*
G01Y147500D02*
X386490D01*
G01X383850Y150600D02*
X384157Y150497D01*
X384387Y150238D01*
X384540Y149928D01*
X384655Y149515D01*
X384693Y149050D01*
X384655Y148585D01*
X384540Y148172D01*
X384387Y147862D01*
X384157Y147603D01*
X383850Y147500D01*
X383543Y147603D01*
X383313Y147862D01*
X383160Y148172D01*
X383045Y148585D01*
X383007Y149050D01*
X383045Y149515D01*
X383160Y149928D01*
X383313Y150238D01*
X383543Y150497D01*
X383850Y150600D01*
G01X395807Y166342D02*
X396037Y166497D01*
X396305Y166600D01*
X396612D01*
X396957Y166445D01*
X397225Y166187D01*
X397417Y165877D01*
X397570Y165360D01*
X397608Y164895D01*
X397532Y164430D01*
X397417Y164120D01*
X397187Y163810D01*
X396918Y163603D01*
X396650Y163500D01*
X396382D01*
X396113Y163603D01*
X395883Y163758D01*
X395692Y163965D01*
G01X394278Y166083D02*
X394048Y166393D01*
X393780Y166548D01*
X393473Y166600D01*
X393090Y166497D01*
X392822Y166238D01*
X392745Y165928D01*
X392783Y165618D01*
X392937Y165360D01*
X393703Y164843D01*
X394048Y164482D01*
X394278Y163965D01*
X394355Y163500D01*
X392745D01*
G01X390450Y166600D02*
X390757Y166497D01*
X390987Y166238D01*
X391140Y165928D01*
X391255Y165515D01*
X391293Y165050D01*
X391255Y164585D01*
X391140Y164172D01*
X390987Y163862D01*
X390757Y163603D01*
X390450Y163500D01*
X390143Y163603D01*
X389913Y163862D01*
X389760Y164172D01*
X389645Y164585D01*
X389607Y165050D01*
X389645Y165515D01*
X389760Y165928D01*
X389913Y166238D01*
X390143Y166497D01*
X390450Y166600D01*
G01X388002Y163862D02*
X387733Y163603D01*
X387427Y163500D01*
X387120Y163603D01*
X386852Y163913D01*
X386660Y164378D01*
X386583Y164843D01*
Y165412D01*
X386660Y165877D01*
X386852Y166290D01*
X387082Y166497D01*
X387350Y166600D01*
X387657Y166497D01*
X387887Y166290D01*
X388040Y165980D01*
X388117Y165567D01*
X388040Y165205D01*
X387848Y164843D01*
X387618Y164637D01*
X387350Y164585D01*
X387043Y164688D01*
X386813Y164947D01*
X386583Y165412D01*
G01X387807Y176342D02*
X388037Y176497D01*
X388305Y176600D01*
X388612D01*
X388957Y176445D01*
X389225Y176187D01*
X389417Y175877D01*
X389570Y175360D01*
X389608Y174895D01*
X389532Y174430D01*
X389417Y174120D01*
X389187Y173810D01*
X388918Y173603D01*
X388650Y173500D01*
X388382D01*
X388113Y173603D01*
X387883Y173758D01*
X387692Y173965D01*
G01X385550Y173500D02*
Y176600D01*
X386010Y175980D01*
G01Y173500D02*
X385090D01*
G01X382450Y176600D02*
X382757Y176497D01*
X382987Y176238D01*
X383140Y175928D01*
X383255Y175515D01*
X383293Y175050D01*
X383255Y174585D01*
X383140Y174172D01*
X382987Y173862D01*
X382757Y173603D01*
X382450Y173500D01*
X382143Y173603D01*
X381913Y173862D01*
X381760Y174172D01*
X381645Y174585D01*
X381607Y175050D01*
X381645Y175515D01*
X381760Y175928D01*
X381913Y176238D01*
X382143Y176497D01*
X382450Y176600D01*
G01X378890Y173500D02*
Y176600D01*
X380308Y174378D01*
X378392D01*
G01X394390Y170694D02*
X394545Y170464D01*
X394648Y170196D01*
Y169889D01*
X394493Y169544D01*
X394235Y169276D01*
X393925Y169084D01*
X393408Y168931D01*
X392943Y168893D01*
X392478Y168969D01*
X392168Y169084D01*
X391858Y169314D01*
X391651Y169583D01*
X391548Y169851D01*
Y170119D01*
X391651Y170388D01*
X391806Y170618D01*
X392013Y170809D01*
G01X394131Y172223D02*
X394441Y172453D01*
X394596Y172721D01*
X394648Y173028D01*
X394545Y173411D01*
X394286Y173679D01*
X393976Y173756D01*
X393666Y173718D01*
X393408Y173564D01*
X392891Y172798D01*
X392530Y172453D01*
X392013Y172223D01*
X391548Y172146D01*
Y173756D01*
G01X394648Y176051D02*
X394545Y175744D01*
X394286Y175514D01*
X393976Y175361D01*
X393563Y175246D01*
X393098Y175208D01*
X392633Y175246D01*
X392220Y175361D01*
X391910Y175514D01*
X391651Y175744D01*
X391548Y176051D01*
X391651Y176358D01*
X391910Y176588D01*
X392220Y176741D01*
X392633Y176856D01*
X393098Y176894D01*
X393563Y176856D01*
X393976Y176741D01*
X394286Y176588D01*
X394545Y176358D01*
X394648Y176051D01*
G01X392013Y178308D02*
X391755Y178538D01*
X391600Y178806D01*
X391548Y179151D01*
X391651Y179496D01*
X391858Y179764D01*
X392220Y179956D01*
X392633Y179994D01*
X393046Y179918D01*
X393305Y179726D01*
X393511Y179458D01*
X393563Y179189D01*
X393511Y178921D01*
X393305Y178576D01*
X394648Y178691D01*
Y179726D01*
G01X399807Y193842D02*
X400037Y193997D01*
X400305Y194100D01*
X400612D01*
X400957Y193945D01*
X401225Y193687D01*
X401417Y193377D01*
X401570Y192860D01*
X401608Y192395D01*
X401532Y191930D01*
X401417Y191620D01*
X401187Y191310D01*
X400918Y191103D01*
X400650Y191000D01*
X400382D01*
X400113Y191103D01*
X399883Y191258D01*
X399692Y191465D01*
G01X397550Y191000D02*
Y194100D01*
X398010Y193480D01*
G01Y191000D02*
X397090D01*
G01X395178Y192292D02*
X394910Y192653D01*
X394680Y192860D01*
X394373Y192963D01*
X394105Y192860D01*
X393913Y192653D01*
X393760Y192343D01*
X393722Y191982D01*
X393760Y191672D01*
X393913Y191362D01*
X394143Y191103D01*
X394412Y191000D01*
X394718Y191103D01*
X394987Y191413D01*
X395140Y191878D01*
X395178Y192395D01*
X395102Y193067D01*
X394987Y193428D01*
X394795Y193790D01*
X394527Y194048D01*
X394258Y194100D01*
X393990Y193997D01*
X393798Y193738D01*
G01X391427Y191000D02*
X391350Y191672D01*
X391235Y192240D01*
X391082Y192757D01*
X390890Y193325D01*
X390583Y194100D01*
X392117D01*
G01X398874Y201383D02*
X399104Y201538D01*
X399372Y201641D01*
X399679D01*
X400024Y201486D01*
X400292Y201228D01*
X400484Y200918D01*
X400637Y200401D01*
X400675Y199936D01*
X400599Y199471D01*
X400484Y199161D01*
X400254Y198851D01*
X399985Y198644D01*
X399717Y198541D01*
X399449D01*
X399180Y198644D01*
X398950Y198799D01*
X398759Y199006D01*
G01X397345Y201124D02*
X397115Y201434D01*
X396847Y201589D01*
X396540Y201641D01*
X396157Y201538D01*
X395889Y201279D01*
X395812Y200969D01*
X395850Y200659D01*
X396004Y200401D01*
X396770Y199884D01*
X397115Y199523D01*
X397345Y199006D01*
X397422Y198541D01*
X395812D01*
G01X393517D02*
Y201641D01*
X393977Y201021D01*
G01Y198541D02*
X393057D01*
G01X390417D02*
Y201641D01*
X390877Y201021D01*
G01Y198541D02*
X389957D01*
G01X398874Y185635D02*
X399104Y185790D01*
X399372Y185893D01*
X399679D01*
X400024Y185738D01*
X400292Y185480D01*
X400484Y185170D01*
X400637Y184653D01*
X400675Y184188D01*
X400599Y183723D01*
X400484Y183413D01*
X400254Y183103D01*
X399985Y182896D01*
X399717Y182793D01*
X399449D01*
X399180Y182896D01*
X398950Y183051D01*
X398759Y183258D01*
G01X397345Y185376D02*
X397115Y185686D01*
X396847Y185841D01*
X396540Y185893D01*
X396157Y185790D01*
X395889Y185531D01*
X395812Y185221D01*
X395850Y184911D01*
X396004Y184653D01*
X396770Y184136D01*
X397115Y183775D01*
X397345Y183258D01*
X397422Y182793D01*
X395812D01*
G01X393517Y185893D02*
X393824Y185790D01*
X394054Y185531D01*
X394207Y185221D01*
X394322Y184808D01*
X394360Y184343D01*
X394322Y183878D01*
X394207Y183465D01*
X394054Y183155D01*
X393824Y182896D01*
X393517Y182793D01*
X393210Y182896D01*
X392980Y183155D01*
X392827Y183465D01*
X392712Y183878D01*
X392674Y184343D01*
X392712Y184808D01*
X392827Y185221D01*
X392980Y185531D01*
X393210Y185790D01*
X393517Y185893D01*
G01X391260Y183413D02*
X391030Y183051D01*
X390724Y182845D01*
X390379Y182793D01*
X390072Y182845D01*
X389765Y183103D01*
X389574Y183413D01*
X389535Y183723D01*
X389612Y184085D01*
X389880Y184343D01*
X390149Y184446D01*
X390494D01*
G01X390149D02*
X389919Y184601D01*
X389727Y184860D01*
X389650Y185170D01*
X389727Y185480D01*
X389919Y185738D01*
X390264Y185893D01*
X390609Y185841D01*
X390954Y185635D01*
G01X398873Y205320D02*
X399103Y205475D01*
X399371Y205578D01*
X399678D01*
X400023Y205423D01*
X400291Y205165D01*
X400483Y204855D01*
X400636Y204338D01*
X400674Y203873D01*
X400598Y203408D01*
X400483Y203098D01*
X400253Y202788D01*
X399984Y202581D01*
X399716Y202478D01*
X399448D01*
X399179Y202581D01*
X398949Y202736D01*
X398758Y202943D01*
G01X396616Y202478D02*
Y205578D01*
X397076Y204958D01*
G01Y202478D02*
X396156D01*
G01X394359Y202943D02*
X394129Y202685D01*
X393861Y202530D01*
X393516Y202478D01*
X393171Y202581D01*
X392903Y202788D01*
X392711Y203150D01*
X392673Y203563D01*
X392749Y203976D01*
X392941Y204235D01*
X393209Y204441D01*
X393478Y204493D01*
X393746Y204441D01*
X394091Y204235D01*
X393976Y205578D01*
X392941D01*
G01X390493Y202478D02*
X390416Y203150D01*
X390301Y203718D01*
X390148Y204235D01*
X389956Y204803D01*
X389649Y205578D01*
X391183D01*
G01X396307Y211842D02*
X396537Y211997D01*
X396805Y212100D01*
X397112D01*
X397457Y211945D01*
X397725Y211687D01*
X397917Y211377D01*
X398070Y210860D01*
X398108Y210395D01*
X398032Y209930D01*
X397917Y209620D01*
X397687Y209310D01*
X397418Y209103D01*
X397150Y209000D01*
X396882D01*
X396613Y209103D01*
X396383Y209258D01*
X396192Y209465D01*
G01X394050Y209000D02*
Y212100D01*
X394510Y211480D01*
G01Y209000D02*
X393590D01*
G01X390490D02*
Y212100D01*
X391908Y209878D01*
X389992D01*
G01X387850Y212100D02*
X388157Y211997D01*
X388387Y211738D01*
X388540Y211428D01*
X388655Y211015D01*
X388693Y210550D01*
X388655Y210085D01*
X388540Y209672D01*
X388387Y209362D01*
X388157Y209103D01*
X387850Y209000D01*
X387543Y209103D01*
X387313Y209362D01*
X387160Y209672D01*
X387045Y210085D01*
X387007Y210550D01*
X387045Y211015D01*
X387160Y211428D01*
X387313Y211738D01*
X387543Y211997D01*
X387850Y212100D01*
G01X394936Y217131D02*
X395166Y217286D01*
X395434Y217389D01*
X395741D01*
X396086Y217234D01*
X396354Y216976D01*
X396546Y216666D01*
X396699Y216149D01*
X396737Y215684D01*
X396661Y215219D01*
X396546Y214909D01*
X396316Y214599D01*
X396047Y214392D01*
X395779Y214289D01*
X395511D01*
X395242Y214392D01*
X395012Y214547D01*
X394821Y214754D01*
G01X393407Y216872D02*
X393177Y217182D01*
X392909Y217337D01*
X392602Y217389D01*
X392219Y217286D01*
X391951Y217027D01*
X391874Y216717D01*
X391912Y216407D01*
X392066Y216149D01*
X392832Y215632D01*
X393177Y215271D01*
X393407Y214754D01*
X393484Y214289D01*
X391874D01*
G01X389579D02*
Y217389D01*
X390039Y216769D01*
G01Y214289D02*
X389119D01*
G01X387207Y215581D02*
X386939Y215942D01*
X386709Y216149D01*
X386402Y216252D01*
X386134Y216149D01*
X385942Y215942D01*
X385789Y215632D01*
X385751Y215271D01*
X385789Y214961D01*
X385942Y214651D01*
X386172Y214392D01*
X386441Y214289D01*
X386747Y214392D01*
X387016Y214702D01*
X387169Y215167D01*
X387207Y215684D01*
X387131Y216356D01*
X387016Y216717D01*
X386824Y217079D01*
X386556Y217337D01*
X386287Y217389D01*
X386019Y217286D01*
X385827Y217027D01*
G01X390866Y247683D02*
X393966D01*
Y248642D01*
X393811Y248948D01*
X393604Y249140D01*
X393191Y249217D01*
X392778Y249140D01*
X392519Y248910D01*
X392364Y248642D01*
Y247683D01*
G01Y248642D02*
X390866Y249217D01*
G01Y251550D02*
X393966D01*
X393346Y251090D01*
G01X390866D02*
Y252010D01*
G01Y254573D02*
X391538Y254650D01*
X392106Y254765D01*
X392623Y254918D01*
X393191Y255110D01*
X393966Y255417D01*
Y253883D01*
G01X391486Y256907D02*
X391124Y257137D01*
X390918Y257443D01*
X390866Y257788D01*
X390918Y258095D01*
X391176Y258402D01*
X391486Y258593D01*
X391796Y258632D01*
X392158Y258555D01*
X392416Y258287D01*
X392519Y258018D01*
Y257673D01*
G01Y258018D02*
X392674Y258248D01*
X392933Y258440D01*
X393243Y258517D01*
X393553Y258440D01*
X393811Y258248D01*
X393966Y257903D01*
X393914Y257558D01*
X393708Y257213D01*
G01X384966Y247683D02*
X388066D01*
Y248642D01*
X387911Y248948D01*
X387704Y249140D01*
X387291Y249217D01*
X386878Y249140D01*
X386619Y248910D01*
X386464Y248642D01*
Y247683D01*
G01Y248642D02*
X384966Y249217D01*
G01X387549Y250822D02*
X387859Y251052D01*
X388014Y251320D01*
X388066Y251627D01*
X387963Y252010D01*
X387704Y252278D01*
X387394Y252355D01*
X387084Y252317D01*
X386826Y252163D01*
X386309Y251397D01*
X385948Y251052D01*
X385431Y250822D01*
X384966Y250745D01*
Y252355D01*
G01Y254650D02*
X385018Y254918D01*
X385173Y255225D01*
X385431Y255417D01*
X385793Y255493D01*
X386154Y255417D01*
X386464Y255187D01*
X386619Y254842D01*
Y254458D01*
X386723Y254228D01*
X386981Y254037D01*
X387343Y253960D01*
X387704Y254075D01*
X387963Y254343D01*
X388066Y254650D01*
X387963Y254957D01*
X387704Y255225D01*
X387343Y255340D01*
X386981Y255263D01*
X386723Y255072D01*
X386619Y254842D01*
Y254458D01*
X386464Y254113D01*
X386154Y253883D01*
X385793Y253807D01*
X385431Y253883D01*
X385173Y254075D01*
X385018Y254382D01*
X384966Y254650D01*
G01Y258210D02*
X388066D01*
X385844Y256792D01*
Y258708D01*
G01X379066Y247683D02*
X382166D01*
Y248642D01*
X382011Y248948D01*
X381804Y249140D01*
X381391Y249217D01*
X380978Y249140D01*
X380719Y248910D01*
X380564Y248642D01*
Y247683D01*
G01Y248642D02*
X379066Y249217D01*
G01X381649Y250822D02*
X381959Y251052D01*
X382114Y251320D01*
X382166Y251627D01*
X382063Y252010D01*
X381804Y252278D01*
X381494Y252355D01*
X381184Y252317D01*
X380926Y252163D01*
X380409Y251397D01*
X380048Y251052D01*
X379531Y250822D01*
X379066Y250745D01*
Y252355D01*
G01Y254650D02*
X379118Y254918D01*
X379273Y255225D01*
X379531Y255417D01*
X379893Y255493D01*
X380254Y255417D01*
X380564Y255187D01*
X380719Y254842D01*
Y254458D01*
X380823Y254228D01*
X381081Y254037D01*
X381443Y253960D01*
X381804Y254075D01*
X382063Y254343D01*
X382166Y254650D01*
X382063Y254957D01*
X381804Y255225D01*
X381443Y255340D01*
X381081Y255263D01*
X380823Y255072D01*
X380719Y254842D01*
Y254458D01*
X380564Y254113D01*
X380254Y253883D01*
X379893Y253807D01*
X379531Y253883D01*
X379273Y254075D01*
X379118Y254382D01*
X379066Y254650D01*
G01X380358Y257022D02*
X380719Y257290D01*
X380926Y257520D01*
X381029Y257827D01*
X380926Y258095D01*
X380719Y258287D01*
X380409Y258440D01*
X380048Y258478D01*
X379738Y258440D01*
X379428Y258287D01*
X379169Y258057D01*
X379066Y257788D01*
X379169Y257482D01*
X379479Y257213D01*
X379944Y257060D01*
X380461Y257022D01*
X381133Y257098D01*
X381494Y257213D01*
X381856Y257405D01*
X382114Y257673D01*
X382166Y257942D01*
X382063Y258210D01*
X381804Y258402D01*
G01X398917Y307500D02*
Y310600D01*
X397958D01*
X397652Y310445D01*
X397460Y310238D01*
X397383Y309825D01*
X397460Y309412D01*
X397690Y309153D01*
X397958Y308998D01*
X398917D01*
G01X397958D02*
X397383Y307500D01*
G01X395050D02*
Y310600D01*
X395510Y309980D01*
G01Y307500D02*
X394590D01*
G01X392678Y308792D02*
X392410Y309153D01*
X392180Y309360D01*
X391873Y309463D01*
X391605Y309360D01*
X391413Y309153D01*
X391260Y308843D01*
X391222Y308482D01*
X391260Y308172D01*
X391413Y307862D01*
X391643Y307603D01*
X391912Y307500D01*
X392218Y307603D01*
X392487Y307913D01*
X392640Y308378D01*
X392678Y308895D01*
X392602Y309567D01*
X392487Y309928D01*
X392295Y310290D01*
X392027Y310548D01*
X391758Y310600D01*
X391490Y310497D01*
X391298Y310238D01*
G01X389693Y307965D02*
X389463Y307707D01*
X389195Y307552D01*
X388850Y307500D01*
X388505Y307603D01*
X388237Y307810D01*
X388045Y308172D01*
X388007Y308585D01*
X388083Y308998D01*
X388275Y309257D01*
X388543Y309463D01*
X388812Y309515D01*
X389080Y309463D01*
X389425Y309257D01*
X389310Y310600D01*
X388275D01*
G01X404817Y322866D02*
Y325966D01*
X403858D01*
X403552Y325811D01*
X403360Y325604D01*
X403283Y325191D01*
X403360Y324778D01*
X403590Y324519D01*
X403858Y324364D01*
X404817D01*
G01X403858D02*
X403283Y322866D01*
G01X400490D02*
Y325966D01*
X401908Y323744D01*
X399992D01*
G01X398693Y323331D02*
X398463Y323073D01*
X398195Y322918D01*
X397850Y322866D01*
X397505Y322969D01*
X397237Y323176D01*
X397045Y323538D01*
X397007Y323951D01*
X397083Y324364D01*
X397275Y324623D01*
X397543Y324829D01*
X397812Y324881D01*
X398080Y324829D01*
X398425Y324623D01*
X398310Y325966D01*
X397275D01*
G01X394750Y322866D02*
X394482Y322918D01*
X394175Y323073D01*
X393983Y323331D01*
X393907Y323693D01*
X393983Y324054D01*
X394213Y324364D01*
X394558Y324519D01*
X394942D01*
X395172Y324623D01*
X395363Y324881D01*
X395440Y325243D01*
X395325Y325604D01*
X395057Y325863D01*
X394750Y325966D01*
X394443Y325863D01*
X394175Y325604D01*
X394060Y325243D01*
X394137Y324881D01*
X394328Y324623D01*
X394558Y324519D01*
X394942D01*
X395287Y324364D01*
X395517Y324054D01*
X395593Y323693D01*
X395517Y323331D01*
X395325Y323073D01*
X395018Y322918D01*
X394750Y322866D01*
G01X404817Y328066D02*
Y331166D01*
X403858D01*
X403552Y331011D01*
X403360Y330804D01*
X403283Y330391D01*
X403360Y329978D01*
X403590Y329719D01*
X403858Y329564D01*
X404817D01*
G01X403858D02*
X403283Y328066D01*
G01X400490D02*
Y331166D01*
X401908Y328944D01*
X399992D01*
G01X398693Y328531D02*
X398463Y328273D01*
X398195Y328118D01*
X397850Y328066D01*
X397505Y328169D01*
X397237Y328376D01*
X397045Y328738D01*
X397007Y329151D01*
X397083Y329564D01*
X397275Y329823D01*
X397543Y330029D01*
X397812Y330081D01*
X398080Y330029D01*
X398425Y329823D01*
X398310Y331166D01*
X397275D01*
G01X394827Y328066D02*
X394750Y328738D01*
X394635Y329306D01*
X394482Y329823D01*
X394290Y330391D01*
X393983Y331166D01*
X395517D01*
G01X391417Y374766D02*
Y377866D01*
X390458D01*
X390152Y377711D01*
X389960Y377504D01*
X389883Y377091D01*
X389960Y376678D01*
X390190Y376419D01*
X390458Y376264D01*
X391417D01*
G01X390458D02*
X389883Y374766D01*
G01X387090D02*
Y377866D01*
X388508Y375644D01*
X386592D01*
G01X385293Y375231D02*
X385063Y374973D01*
X384795Y374818D01*
X384450Y374766D01*
X384105Y374869D01*
X383837Y375076D01*
X383645Y375438D01*
X383607Y375851D01*
X383683Y376264D01*
X383875Y376523D01*
X384143Y376729D01*
X384412Y376781D01*
X384680Y376729D01*
X385025Y376523D01*
X384910Y377866D01*
X383875D01*
G01X381350Y374766D02*
Y377866D01*
X381810Y377246D01*
G01Y374766D02*
X380890D01*
G01X391417Y379966D02*
Y383066D01*
X390458D01*
X390152Y382911D01*
X389960Y382704D01*
X389883Y382291D01*
X389960Y381878D01*
X390190Y381619D01*
X390458Y381464D01*
X391417D01*
G01X390458D02*
X389883Y379966D01*
G01X387090D02*
Y383066D01*
X388508Y380844D01*
X386592D01*
G01X385293Y380431D02*
X385063Y380173D01*
X384795Y380018D01*
X384450Y379966D01*
X384105Y380069D01*
X383837Y380276D01*
X383645Y380638D01*
X383607Y381051D01*
X383683Y381464D01*
X383875Y381723D01*
X384143Y381929D01*
X384412Y381981D01*
X384680Y381929D01*
X385025Y381723D01*
X384910Y383066D01*
X383875D01*
G01X381350D02*
X381657Y382963D01*
X381887Y382704D01*
X382040Y382394D01*
X382155Y381981D01*
X382193Y381516D01*
X382155Y381051D01*
X382040Y380638D01*
X381887Y380328D01*
X381657Y380069D01*
X381350Y379966D01*
X381043Y380069D01*
X380813Y380328D01*
X380660Y380638D01*
X380545Y381051D01*
X380507Y381516D01*
X380545Y381981D01*
X380660Y382394D01*
X380813Y382704D01*
X381043Y382963D01*
X381350Y383066D01*
G01X398327Y140635D02*
X398482Y140405D01*
X398585Y140137D01*
Y139830D01*
X398430Y139485D01*
X398172Y139217D01*
X397862Y139025D01*
X397345Y138872D01*
X396880Y138834D01*
X396415Y138910D01*
X396105Y139025D01*
X395795Y139255D01*
X395588Y139524D01*
X395485Y139792D01*
Y140060D01*
X395588Y140329D01*
X395743Y140559D01*
X395950Y140750D01*
G01X398068Y142164D02*
X398378Y142394D01*
X398533Y142662D01*
X398585Y142969D01*
X398482Y143352D01*
X398223Y143620D01*
X397913Y143697D01*
X397603Y143659D01*
X397345Y143505D01*
X396828Y142739D01*
X396467Y142394D01*
X395950Y142164D01*
X395485Y142087D01*
Y143697D01*
G01Y145992D02*
X398585D01*
X397965Y145532D01*
G01X395485D02*
Y146452D01*
G01Y149015D02*
X396157Y149092D01*
X396725Y149207D01*
X397242Y149360D01*
X397810Y149552D01*
X398585Y149859D01*
Y148325D01*
G01X405652Y136354D02*
X405777Y136194D01*
X405860Y136007D01*
Y135794D01*
X405735Y135554D01*
X405527Y135367D01*
X405277Y135234D01*
X404860Y135127D01*
X404485Y135100D01*
X404110Y135154D01*
X403860Y135234D01*
X403610Y135394D01*
X403443Y135580D01*
X403360Y135767D01*
Y135954D01*
X403443Y136140D01*
X403568Y136300D01*
X403735Y136434D01*
G01X405443Y137460D02*
X405693Y137620D01*
X405818Y137807D01*
X405860Y138020D01*
X405777Y138287D01*
X405568Y138474D01*
X405318Y138527D01*
X405068Y138500D01*
X404860Y138394D01*
X404443Y137860D01*
X404152Y137620D01*
X403735Y137460D01*
X403360Y137407D01*
Y138527D01*
G01Y140167D02*
X405860D01*
X405360Y139847D01*
G01X403360D02*
Y140487D01*
G01X403860Y141780D02*
X403568Y141940D01*
X403402Y142154D01*
X403360Y142394D01*
X403402Y142607D01*
X403610Y142820D01*
X403860Y142954D01*
X404110Y142980D01*
X404402Y142927D01*
X404610Y142740D01*
X404693Y142554D01*
Y142314D01*
G01Y142554D02*
X404818Y142714D01*
X405027Y142847D01*
X405277Y142900D01*
X405527Y142847D01*
X405735Y142714D01*
X405860Y142474D01*
X405818Y142234D01*
X405652Y141994D01*
G01X402042Y142787D02*
X402167Y142627D01*
X402250Y142440D01*
Y142227D01*
X402125Y141987D01*
X401917Y141800D01*
X401667Y141667D01*
X401250Y141560D01*
X400875Y141533D01*
X400500Y141587D01*
X400250Y141667D01*
X400000Y141827D01*
X399833Y142013D01*
X399750Y142200D01*
Y142387D01*
X399833Y142573D01*
X399958Y142733D01*
X400125Y142867D01*
G01X399750Y144400D02*
X402250D01*
X401750Y144080D01*
G01X399750D02*
Y144720D01*
G01X401833Y146093D02*
X402083Y146253D01*
X402208Y146440D01*
X402250Y146653D01*
X402167Y146920D01*
X401958Y147107D01*
X401708Y147160D01*
X401458Y147133D01*
X401250Y147027D01*
X400833Y146493D01*
X400542Y146253D01*
X400125Y146093D01*
X399750Y146040D01*
Y147160D01*
G01Y149120D02*
X402250D01*
X400458Y148133D01*
Y149467D01*
G01X405750Y145667D02*
X408250D01*
Y146333D01*
X408125Y146547D01*
X407958Y146680D01*
X407625Y146733D01*
X407292Y146680D01*
X407083Y146520D01*
X406958Y146333D01*
Y145667D01*
G01Y146333D02*
X405750Y146733D01*
G01Y148400D02*
X408250D01*
X407750Y148080D01*
G01X405750D02*
Y148720D01*
G01X406042Y150147D02*
X405833Y150333D01*
X405750Y150547D01*
X405833Y150760D01*
X406083Y150947D01*
X406458Y151080D01*
X406833Y151133D01*
X407292D01*
X407667Y151080D01*
X408000Y150947D01*
X408167Y150787D01*
X408250Y150600D01*
X408167Y150387D01*
X408000Y150227D01*
X407750Y150120D01*
X407417Y150067D01*
X407125Y150120D01*
X406833Y150253D01*
X406667Y150413D01*
X406625Y150600D01*
X406708Y150813D01*
X406917Y150973D01*
X407292Y151133D01*
G01X405750Y152747D02*
X406292Y152800D01*
X406750Y152880D01*
X407167Y152987D01*
X407625Y153120D01*
X408250Y153333D01*
Y152267D01*
G01X401792Y161287D02*
X401917Y161127D01*
X402000Y160940D01*
Y160727D01*
X401875Y160487D01*
X401667Y160300D01*
X401417Y160167D01*
X401000Y160060D01*
X400625Y160033D01*
X400250Y160087D01*
X400000Y160167D01*
X399750Y160327D01*
X399583Y160513D01*
X399500Y160700D01*
Y160887D01*
X399583Y161073D01*
X399708Y161233D01*
X399875Y161367D01*
G01X399500Y162900D02*
X402000D01*
X401500Y162580D01*
G01X399500D02*
Y163220D01*
G01X400000Y164513D02*
X399708Y164673D01*
X399542Y164887D01*
X399500Y165127D01*
X399542Y165340D01*
X399750Y165553D01*
X400000Y165687D01*
X400250Y165713D01*
X400542Y165660D01*
X400750Y165473D01*
X400833Y165287D01*
Y165047D01*
G01Y165287D02*
X400958Y165447D01*
X401167Y165580D01*
X401417Y165633D01*
X401667Y165580D01*
X401875Y165447D01*
X402000Y165207D01*
X401958Y164967D01*
X401792Y164727D01*
G01X399500Y167300D02*
X402000D01*
X401500Y166980D01*
G01X399500D02*
Y167620D01*
G01X417465Y149652D02*
X417625Y149777D01*
X417812Y149860D01*
X418025D01*
X418265Y149735D01*
X418452Y149527D01*
X418585Y149277D01*
X418692Y148860D01*
X418719Y148485D01*
X418665Y148110D01*
X418585Y147860D01*
X418425Y147610D01*
X418239Y147443D01*
X418052Y147360D01*
X417865D01*
X417679Y147443D01*
X417519Y147568D01*
X417385Y147735D01*
G01X415852Y147360D02*
Y149860D01*
X416172Y149360D01*
G01Y147360D02*
X415532D01*
G01X413332D02*
Y149860D01*
X414319Y148068D01*
X412985D01*
G01X411959Y148402D02*
X411772Y148693D01*
X411612Y148860D01*
X411399Y148943D01*
X411212Y148860D01*
X411079Y148693D01*
X410972Y148443D01*
X410945Y148152D01*
X410972Y147902D01*
X411079Y147652D01*
X411239Y147443D01*
X411425Y147360D01*
X411639Y147443D01*
X411825Y147693D01*
X411932Y148068D01*
X411959Y148485D01*
X411905Y149027D01*
X411825Y149318D01*
X411692Y149610D01*
X411505Y149818D01*
X411319Y149860D01*
X411132Y149777D01*
X410999Y149568D01*
G01X417465Y153589D02*
X417625Y153714D01*
X417812Y153797D01*
X418025D01*
X418265Y153672D01*
X418452Y153464D01*
X418585Y153214D01*
X418692Y152797D01*
X418719Y152422D01*
X418665Y152047D01*
X418585Y151797D01*
X418425Y151547D01*
X418239Y151380D01*
X418052Y151297D01*
X417865D01*
X417679Y151380D01*
X417519Y151505D01*
X417385Y151672D01*
G01X416359Y153380D02*
X416199Y153630D01*
X416012Y153755D01*
X415799Y153797D01*
X415532Y153714D01*
X415345Y153505D01*
X415292Y153255D01*
X415319Y153005D01*
X415425Y152797D01*
X415959Y152380D01*
X416199Y152089D01*
X416359Y151672D01*
X416412Y151297D01*
X415292D01*
G01X413652Y153797D02*
X413865Y153714D01*
X414025Y153505D01*
X414132Y153255D01*
X414212Y152922D01*
X414239Y152547D01*
X414212Y152172D01*
X414132Y151839D01*
X414025Y151589D01*
X413865Y151380D01*
X413652Y151297D01*
X413439Y151380D01*
X413279Y151589D01*
X413172Y151839D01*
X413092Y152172D01*
X413065Y152547D01*
X413092Y152922D01*
X413172Y153255D01*
X413279Y153505D01*
X413439Y153714D01*
X413652Y153797D01*
G01X411132Y151297D02*
Y153797D01*
X412119Y152005D01*
X410785D01*
G01X414028Y164913D02*
X414153Y164753D01*
X414236Y164566D01*
Y164353D01*
X414111Y164113D01*
X413903Y163926D01*
X413653Y163793D01*
X413236Y163686D01*
X412861Y163659D01*
X412486Y163713D01*
X412236Y163793D01*
X411986Y163953D01*
X411819Y164139D01*
X411736Y164326D01*
Y164513D01*
X411819Y164699D01*
X411944Y164859D01*
X412111Y164993D01*
G01X413819Y166019D02*
X414069Y166179D01*
X414194Y166366D01*
X414236Y166579D01*
X414153Y166846D01*
X413944Y167033D01*
X413694Y167086D01*
X413444Y167059D01*
X413236Y166953D01*
X412819Y166419D01*
X412528Y166179D01*
X412111Y166019D01*
X411736Y165966D01*
Y167086D01*
G01X413819Y168219D02*
X414069Y168379D01*
X414194Y168566D01*
X414236Y168779D01*
X414153Y169046D01*
X413944Y169233D01*
X413694Y169286D01*
X413444Y169259D01*
X413236Y169153D01*
X412819Y168619D01*
X412528Y168379D01*
X412111Y168219D01*
X411736Y168166D01*
Y169286D01*
G01X413819Y170419D02*
X414069Y170579D01*
X414194Y170766D01*
X414236Y170979D01*
X414153Y171246D01*
X413944Y171433D01*
X413694Y171486D01*
X413444Y171459D01*
X413236Y171353D01*
X412819Y170819D01*
X412528Y170579D01*
X412111Y170419D01*
X411736Y170366D01*
Y171486D01*
G01X412529Y161463D02*
X412689Y161588D01*
X412876Y161671D01*
X413089D01*
X413329Y161546D01*
X413516Y161338D01*
X413649Y161088D01*
X413756Y160671D01*
X413783Y160296D01*
X413729Y159921D01*
X413649Y159671D01*
X413489Y159421D01*
X413303Y159254D01*
X413116Y159171D01*
X412929D01*
X412743Y159254D01*
X412583Y159379D01*
X412449Y159546D01*
G01X410916Y159171D02*
Y161671D01*
X411236Y161171D01*
G01Y159171D02*
X410596D01*
G01X408716D02*
Y161671D01*
X409036Y161171D01*
G01Y159171D02*
X408396D01*
G01X406516D02*
Y161671D01*
X406836Y161171D01*
G01Y159171D02*
X406196D01*
G01X405652Y159977D02*
X405777Y159817D01*
X405860Y159630D01*
Y159417D01*
X405735Y159177D01*
X405527Y158990D01*
X405277Y158857D01*
X404860Y158750D01*
X404485Y158723D01*
X404110Y158777D01*
X403860Y158857D01*
X403610Y159017D01*
X403443Y159203D01*
X403360Y159390D01*
Y159577D01*
X403443Y159763D01*
X403568Y159923D01*
X403735Y160057D01*
G01X403360Y161590D02*
X405860D01*
X405360Y161270D01*
G01X403360D02*
Y161910D01*
G01X405860Y163790D02*
X405777Y163577D01*
X405568Y163417D01*
X405318Y163310D01*
X404985Y163230D01*
X404610Y163203D01*
X404235Y163230D01*
X403902Y163310D01*
X403652Y163417D01*
X403443Y163577D01*
X403360Y163790D01*
X403443Y164003D01*
X403652Y164163D01*
X403902Y164270D01*
X404235Y164350D01*
X404610Y164377D01*
X404985Y164350D01*
X405318Y164270D01*
X405568Y164163D01*
X405777Y164003D01*
X405860Y163790D01*
G01X403735Y165403D02*
X403527Y165563D01*
X403402Y165750D01*
X403360Y165990D01*
X403443Y166230D01*
X403610Y166417D01*
X403902Y166550D01*
X404235Y166577D01*
X404568Y166523D01*
X404777Y166390D01*
X404943Y166203D01*
X404985Y166017D01*
X404943Y165830D01*
X404777Y165590D01*
X405860Y165670D01*
Y166390D01*
G01X412529Y157526D02*
X412689Y157651D01*
X412876Y157734D01*
X413089D01*
X413329Y157609D01*
X413516Y157401D01*
X413649Y157151D01*
X413756Y156734D01*
X413783Y156359D01*
X413729Y155984D01*
X413649Y155734D01*
X413489Y155484D01*
X413303Y155317D01*
X413116Y155234D01*
X412929D01*
X412743Y155317D01*
X412583Y155442D01*
X412449Y155609D01*
G01X410916Y155234D02*
Y157734D01*
X411236Y157234D01*
G01Y155234D02*
X410596D01*
G01X408716D02*
Y157734D01*
X409036Y157234D01*
G01Y155234D02*
X408396D01*
G01X406516D02*
X406329Y155276D01*
X406116Y155401D01*
X405983Y155609D01*
X405929Y155901D01*
X405983Y156192D01*
X406143Y156442D01*
X406383Y156567D01*
X406649D01*
X406809Y156651D01*
X406943Y156859D01*
X406996Y157151D01*
X406916Y157442D01*
X406729Y157651D01*
X406516Y157734D01*
X406303Y157651D01*
X406116Y157442D01*
X406036Y157151D01*
X406089Y156859D01*
X406223Y156651D01*
X406383Y156567D01*
X406649D01*
X406889Y156442D01*
X407049Y156192D01*
X407103Y155901D01*
X407049Y155609D01*
X406916Y155401D01*
X406703Y155276D01*
X406516Y155234D01*
G01X401715Y152103D02*
X401840Y151943D01*
X401923Y151756D01*
Y151543D01*
X401798Y151303D01*
X401590Y151116D01*
X401340Y150983D01*
X400923Y150876D01*
X400548Y150849D01*
X400173Y150903D01*
X399923Y150983D01*
X399673Y151143D01*
X399506Y151329D01*
X399423Y151516D01*
Y151703D01*
X399506Y151889D01*
X399631Y152049D01*
X399798Y152183D01*
G01X401506Y153209D02*
X401756Y153369D01*
X401881Y153556D01*
X401923Y153769D01*
X401840Y154036D01*
X401631Y154223D01*
X401381Y154276D01*
X401131Y154249D01*
X400923Y154143D01*
X400506Y153609D01*
X400215Y153369D01*
X399798Y153209D01*
X399423Y153156D01*
Y154276D01*
G01Y155916D02*
X401923D01*
X401423Y155596D01*
G01X399423D02*
Y156236D01*
G01Y158116D02*
X399465Y158303D01*
X399590Y158516D01*
X399798Y158649D01*
X400090Y158703D01*
X400381Y158649D01*
X400631Y158489D01*
X400756Y158249D01*
Y157983D01*
X400840Y157823D01*
X401048Y157689D01*
X401340Y157636D01*
X401631Y157716D01*
X401840Y157903D01*
X401923Y158116D01*
X401840Y158329D01*
X401631Y158516D01*
X401340Y158596D01*
X401048Y158543D01*
X400840Y158409D01*
X400756Y158249D01*
Y157983D01*
X400631Y157743D01*
X400381Y157583D01*
X400090Y157529D01*
X399798Y157583D01*
X399590Y157716D01*
X399465Y157929D01*
X399423Y158116D01*
G01X412307Y176342D02*
X412537Y176497D01*
X412805Y176600D01*
X413112D01*
X413457Y176445D01*
X413725Y176187D01*
X413917Y175877D01*
X414070Y175360D01*
X414108Y174895D01*
X414032Y174430D01*
X413917Y174120D01*
X413687Y173810D01*
X413418Y173603D01*
X413150Y173500D01*
X412882D01*
X412613Y173603D01*
X412383Y173758D01*
X412192Y173965D01*
G01X410050Y173500D02*
Y176600D01*
X410510Y175980D01*
G01Y173500D02*
X409590D01*
G01X406950D02*
Y176600D01*
X407410Y175980D01*
G01Y173500D02*
X406490D01*
G01X404693Y174120D02*
X404463Y173758D01*
X404157Y173552D01*
X403812Y173500D01*
X403505Y173552D01*
X403198Y173810D01*
X403007Y174120D01*
X402968Y174430D01*
X403045Y174792D01*
X403313Y175050D01*
X403582Y175153D01*
X403927D01*
G01X403582D02*
X403352Y175308D01*
X403160Y175567D01*
X403083Y175877D01*
X403160Y176187D01*
X403352Y176445D01*
X403697Y176600D01*
X404042Y176548D01*
X404387Y176342D01*
G01X406748Y181698D02*
X406978Y181853D01*
X407246Y181956D01*
X407553D01*
X407898Y181801D01*
X408166Y181543D01*
X408358Y181233D01*
X408511Y180716D01*
X408549Y180251D01*
X408473Y179786D01*
X408358Y179476D01*
X408128Y179166D01*
X407859Y178959D01*
X407591Y178856D01*
X407323D01*
X407054Y178959D01*
X406824Y179114D01*
X406633Y179321D01*
G01X404491Y178856D02*
Y181956D01*
X404951Y181336D01*
G01Y178856D02*
X404031D01*
G01X401391Y181956D02*
X401698Y181853D01*
X401928Y181594D01*
X402081Y181284D01*
X402196Y180871D01*
X402234Y180406D01*
X402196Y179941D01*
X402081Y179528D01*
X401928Y179218D01*
X401698Y178959D01*
X401391Y178856D01*
X401084Y178959D01*
X400854Y179218D01*
X400701Y179528D01*
X400586Y179941D01*
X400548Y180406D01*
X400586Y180871D01*
X400701Y181284D01*
X400854Y181594D01*
X401084Y181853D01*
X401391Y181956D01*
G01X399019Y180148D02*
X398751Y180509D01*
X398521Y180716D01*
X398214Y180819D01*
X397946Y180716D01*
X397754Y180509D01*
X397601Y180199D01*
X397563Y179838D01*
X397601Y179528D01*
X397754Y179218D01*
X397984Y178959D01*
X398253Y178856D01*
X398559Y178959D01*
X398828Y179269D01*
X398981Y179734D01*
X399019Y180251D01*
X398943Y180923D01*
X398828Y181284D01*
X398636Y181646D01*
X398368Y181904D01*
X398099Y181956D01*
X397831Y181853D01*
X397639Y181594D01*
G01X409333Y168000D02*
Y170500D01*
X408667D01*
X408453Y170375D01*
X408320Y170208D01*
X408267Y169875D01*
X408320Y169542D01*
X408480Y169333D01*
X408667Y169208D01*
X409333D01*
G01X408667D02*
X408267Y168000D01*
G01X406600D02*
Y170500D01*
X406920Y170000D01*
G01Y168000D02*
X406280D01*
G01X404853Y168292D02*
X404667Y168083D01*
X404453Y168000D01*
X404240Y168083D01*
X404053Y168333D01*
X403920Y168708D01*
X403867Y169083D01*
Y169542D01*
X403920Y169917D01*
X404053Y170250D01*
X404213Y170417D01*
X404400Y170500D01*
X404613Y170417D01*
X404773Y170250D01*
X404880Y170000D01*
X404933Y169667D01*
X404880Y169375D01*
X404747Y169083D01*
X404587Y168917D01*
X404400Y168875D01*
X404187Y168958D01*
X404027Y169167D01*
X403867Y169542D01*
G01X402200Y168000D02*
X402013Y168042D01*
X401800Y168167D01*
X401667Y168375D01*
X401613Y168667D01*
X401667Y168958D01*
X401827Y169208D01*
X402067Y169333D01*
X402333D01*
X402493Y169417D01*
X402627Y169625D01*
X402680Y169917D01*
X402600Y170208D01*
X402413Y170417D01*
X402200Y170500D01*
X401987Y170417D01*
X401800Y170208D01*
X401720Y169917D01*
X401773Y169625D01*
X401907Y169417D01*
X402067Y169333D01*
X402333D01*
X402573Y169208D01*
X402733Y168958D01*
X402787Y168667D01*
X402733Y168375D01*
X402600Y168167D01*
X402387Y168042D01*
X402200Y168000D01*
G01X404792Y191787D02*
X404917Y191627D01*
X405000Y191440D01*
Y191227D01*
X404875Y190987D01*
X404667Y190800D01*
X404417Y190667D01*
X404000Y190560D01*
X403625Y190533D01*
X403250Y190587D01*
X403000Y190667D01*
X402750Y190827D01*
X402583Y191013D01*
X402500Y191200D01*
Y191387D01*
X402583Y191573D01*
X402708Y191733D01*
X402875Y191867D01*
G01X402500Y193400D02*
X405000D01*
X404500Y193080D01*
G01X402500D02*
Y193720D01*
G01Y195547D02*
X403042Y195600D01*
X403500Y195680D01*
X403917Y195787D01*
X404375Y195920D01*
X405000Y196133D01*
Y195067D01*
G01Y197800D02*
X404917Y197587D01*
X404708Y197427D01*
X404458Y197320D01*
X404125Y197240D01*
X403750Y197213D01*
X403375Y197240D01*
X403042Y197320D01*
X402792Y197427D01*
X402583Y197587D01*
X402500Y197800D01*
X402583Y198013D01*
X402792Y198173D01*
X403042Y198280D01*
X403375Y198360D01*
X403750Y198387D01*
X404125Y198360D01*
X404458Y198280D01*
X404708Y198173D01*
X404917Y198013D01*
X405000Y197800D01*
G01X413528Y196896D02*
X413688Y197021D01*
X413875Y197104D01*
X414088D01*
X414328Y196979D01*
X414515Y196771D01*
X414648Y196521D01*
X414755Y196104D01*
X414782Y195729D01*
X414728Y195354D01*
X414648Y195104D01*
X414488Y194854D01*
X414302Y194687D01*
X414115Y194604D01*
X413928D01*
X413742Y194687D01*
X413582Y194812D01*
X413448Y194979D01*
G01X411915Y194604D02*
Y197104D01*
X412235Y196604D01*
G01Y194604D02*
X411595D01*
G01X410302Y194979D02*
X410142Y194771D01*
X409955Y194646D01*
X409715Y194604D01*
X409475Y194687D01*
X409288Y194854D01*
X409155Y195146D01*
X409128Y195479D01*
X409182Y195812D01*
X409315Y196021D01*
X409502Y196187D01*
X409688Y196229D01*
X409875Y196187D01*
X410115Y196021D01*
X410035Y197104D01*
X409315D01*
G01X408102Y195104D02*
X407942Y194812D01*
X407728Y194646D01*
X407488Y194604D01*
X407275Y194646D01*
X407062Y194854D01*
X406928Y195104D01*
X406902Y195354D01*
X406955Y195646D01*
X407142Y195854D01*
X407328Y195937D01*
X407568D01*
G01X407328D02*
X407168Y196062D01*
X407035Y196271D01*
X406982Y196521D01*
X407035Y196771D01*
X407168Y196979D01*
X407408Y197104D01*
X407648Y197062D01*
X407888Y196896D01*
G01X416213Y205292D02*
X416373Y205417D01*
X416560Y205500D01*
X416773D01*
X417013Y205375D01*
X417200Y205167D01*
X417333Y204917D01*
X417440Y204500D01*
X417467Y204125D01*
X417413Y203750D01*
X417333Y203500D01*
X417173Y203250D01*
X416987Y203083D01*
X416800Y203000D01*
X416613D01*
X416427Y203083D01*
X416267Y203208D01*
X416133Y203375D01*
G01X414600Y203000D02*
Y205500D01*
X414920Y205000D01*
G01Y203000D02*
X414280D01*
G01X412400D02*
Y205500D01*
X412720Y205000D01*
G01Y203000D02*
X412080D01*
G01X410707Y205083D02*
X410547Y205333D01*
X410360Y205458D01*
X410147Y205500D01*
X409880Y205417D01*
X409693Y205208D01*
X409640Y204958D01*
X409667Y204708D01*
X409773Y204500D01*
X410307Y204083D01*
X410547Y203792D01*
X410707Y203375D01*
X410760Y203000D01*
X409640D01*
G01X408307Y222792D02*
X408537Y222947D01*
X408805Y223050D01*
X409112D01*
X409457Y222895D01*
X409725Y222637D01*
X409917Y222327D01*
X410070Y221810D01*
X410108Y221345D01*
X410032Y220880D01*
X409917Y220570D01*
X409687Y220260D01*
X409418Y220053D01*
X409150Y219950D01*
X408882D01*
X408613Y220053D01*
X408383Y220208D01*
X408192Y220415D01*
G01X406050Y219950D02*
Y223050D01*
X406510Y222430D01*
G01Y219950D02*
X405590D01*
G01X403793Y220415D02*
X403563Y220157D01*
X403295Y220002D01*
X402950Y219950D01*
X402605Y220053D01*
X402337Y220260D01*
X402145Y220622D01*
X402107Y221035D01*
X402183Y221448D01*
X402375Y221707D01*
X402643Y221913D01*
X402912Y221965D01*
X403180Y221913D01*
X403525Y221707D01*
X403410Y223050D01*
X402375D01*
G01X400502Y220312D02*
X400233Y220053D01*
X399927Y219950D01*
X399620Y220053D01*
X399352Y220363D01*
X399160Y220828D01*
X399083Y221293D01*
Y221862D01*
X399160Y222327D01*
X399352Y222740D01*
X399582Y222947D01*
X399850Y223050D01*
X400157Y222947D01*
X400387Y222740D01*
X400540Y222430D01*
X400617Y222017D01*
X400540Y221655D01*
X400348Y221293D01*
X400118Y221087D01*
X399850Y221035D01*
X399543Y221138D01*
X399313Y221397D01*
X399083Y221862D01*
G01X407307Y233792D02*
X407537Y233947D01*
X407805Y234050D01*
X408112D01*
X408457Y233895D01*
X408725Y233637D01*
X408917Y233327D01*
X409070Y232810D01*
X409108Y232345D01*
X409032Y231880D01*
X408917Y231570D01*
X408687Y231260D01*
X408418Y231053D01*
X408150Y230950D01*
X407882D01*
X407613Y231053D01*
X407383Y231208D01*
X407192Y231415D01*
G01X405050Y230950D02*
Y234050D01*
X405510Y233430D01*
G01Y230950D02*
X404590D01*
G01X402027D02*
X401950Y231622D01*
X401835Y232190D01*
X401682Y232707D01*
X401490Y233275D01*
X401183Y234050D01*
X402717D01*
G01X399578Y233533D02*
X399348Y233843D01*
X399080Y233998D01*
X398773Y234050D01*
X398390Y233947D01*
X398122Y233688D01*
X398045Y233378D01*
X398083Y233068D01*
X398237Y232810D01*
X399003Y232293D01*
X399348Y231932D01*
X399578Y231415D01*
X399655Y230950D01*
X398045D01*
G01X403182Y247683D02*
X406282D01*
Y248642D01*
X406127Y248948D01*
X405920Y249140D01*
X405507Y249217D01*
X405094Y249140D01*
X404835Y248910D01*
X404680Y248642D01*
Y247683D01*
G01Y248642D02*
X403182Y249217D01*
G01X405765Y250822D02*
X406075Y251052D01*
X406230Y251320D01*
X406282Y251627D01*
X406179Y252010D01*
X405920Y252278D01*
X405610Y252355D01*
X405300Y252317D01*
X405042Y252163D01*
X404525Y251397D01*
X404164Y251052D01*
X403647Y250822D01*
X403182Y250745D01*
Y252355D01*
G01X403544Y253998D02*
X403285Y254267D01*
X403182Y254573D01*
X403285Y254880D01*
X403595Y255148D01*
X404060Y255340D01*
X404525Y255417D01*
X405094D01*
X405559Y255340D01*
X405972Y255148D01*
X406179Y254918D01*
X406282Y254650D01*
X406179Y254343D01*
X405972Y254113D01*
X405662Y253960D01*
X405249Y253883D01*
X404887Y253960D01*
X404525Y254152D01*
X404319Y254382D01*
X404267Y254650D01*
X404370Y254957D01*
X404629Y255187D01*
X405094Y255417D01*
G01X403802Y256907D02*
X403440Y257137D01*
X403234Y257443D01*
X403182Y257788D01*
X403234Y258095D01*
X403492Y258402D01*
X403802Y258593D01*
X404112Y258632D01*
X404474Y258555D01*
X404732Y258287D01*
X404835Y258018D01*
Y257673D01*
G01Y258018D02*
X404990Y258248D01*
X405249Y258440D01*
X405559Y258517D01*
X405869Y258440D01*
X406127Y258248D01*
X406282Y257903D01*
X406230Y257558D01*
X406024Y257213D01*
G01X396250Y247683D02*
X399350D01*
Y248642D01*
X399195Y248948D01*
X398988Y249140D01*
X398575Y249217D01*
X398162Y249140D01*
X397903Y248910D01*
X397748Y248642D01*
Y247683D01*
G01Y248642D02*
X396250Y249217D01*
G01Y251550D02*
X399350D01*
X398730Y251090D01*
G01X396250D02*
Y252010D01*
G01Y254573D02*
X396922Y254650D01*
X397490Y254765D01*
X398007Y254918D01*
X398575Y255110D01*
X399350Y255417D01*
Y253883D01*
G01X396250Y257750D02*
X399350D01*
X398730Y257290D01*
G01X396250D02*
Y258210D01*
G01X408266Y247683D02*
X411366D01*
Y248642D01*
X411211Y248948D01*
X411004Y249140D01*
X410591Y249217D01*
X410178Y249140D01*
X409919Y248910D01*
X409764Y248642D01*
Y247683D01*
G01Y248642D02*
X408266Y249217D01*
G01X408886Y250707D02*
X408524Y250937D01*
X408318Y251243D01*
X408266Y251588D01*
X408318Y251895D01*
X408576Y252202D01*
X408886Y252393D01*
X409196Y252432D01*
X409558Y252355D01*
X409816Y252087D01*
X409919Y251818D01*
Y251473D01*
G01Y251818D02*
X410074Y252048D01*
X410333Y252240D01*
X410643Y252317D01*
X410953Y252240D01*
X411211Y252048D01*
X411366Y251703D01*
X411314Y251358D01*
X411108Y251013D01*
G01X411366Y254650D02*
X411263Y254343D01*
X411004Y254113D01*
X410694Y253960D01*
X410281Y253845D01*
X409816Y253807D01*
X409351Y253845D01*
X408938Y253960D01*
X408628Y254113D01*
X408369Y254343D01*
X408266Y254650D01*
X408369Y254957D01*
X408628Y255187D01*
X408938Y255340D01*
X409351Y255455D01*
X409816Y255493D01*
X410281Y255455D01*
X410694Y255340D01*
X411004Y255187D01*
X411263Y254957D01*
X411366Y254650D01*
G01X408628Y257098D02*
X408369Y257367D01*
X408266Y257673D01*
X408369Y257980D01*
X408679Y258248D01*
X409144Y258440D01*
X409609Y258517D01*
X410178D01*
X410643Y258440D01*
X411056Y258248D01*
X411263Y258018D01*
X411366Y257750D01*
X411263Y257443D01*
X411056Y257213D01*
X410746Y257060D01*
X410333Y256983D01*
X409971Y257060D01*
X409609Y257252D01*
X409403Y257482D01*
X409351Y257750D01*
X409454Y258057D01*
X409713Y258287D01*
X410178Y258517D01*
G01X420507Y286792D02*
X420737Y286947D01*
X421005Y287050D01*
X421312D01*
X421657Y286895D01*
X421925Y286637D01*
X422117Y286327D01*
X422270Y285810D01*
X422308Y285345D01*
X422232Y284880D01*
X422117Y284570D01*
X421887Y284260D01*
X421618Y284053D01*
X421350Y283950D01*
X421082D01*
X420813Y284053D01*
X420583Y284208D01*
X420392Y284415D01*
G01X418978Y286533D02*
X418748Y286843D01*
X418480Y286998D01*
X418173Y287050D01*
X417790Y286947D01*
X417522Y286688D01*
X417445Y286378D01*
X417483Y286068D01*
X417637Y285810D01*
X418403Y285293D01*
X418748Y284932D01*
X418978Y284415D01*
X419055Y283950D01*
X417445D01*
G01X414690D02*
Y287050D01*
X416108Y284828D01*
X414192D01*
G01X412893Y284570D02*
X412663Y284208D01*
X412357Y284002D01*
X412012Y283950D01*
X411705Y284002D01*
X411398Y284260D01*
X411207Y284570D01*
X411168Y284880D01*
X411245Y285242D01*
X411513Y285500D01*
X411782Y285603D01*
X412127D01*
G01X411782D02*
X411552Y285758D01*
X411360Y286017D01*
X411283Y286327D01*
X411360Y286637D01*
X411552Y286895D01*
X411897Y287050D01*
X412242Y286998D01*
X412587Y286792D01*
G01X420507Y294892D02*
X420737Y295047D01*
X421005Y295150D01*
X421312D01*
X421657Y294995D01*
X421925Y294737D01*
X422117Y294427D01*
X422270Y293910D01*
X422308Y293445D01*
X422232Y292980D01*
X422117Y292670D01*
X421887Y292360D01*
X421618Y292153D01*
X421350Y292050D01*
X421082D01*
X420813Y292153D01*
X420583Y292308D01*
X420392Y292515D01*
G01X418978Y294633D02*
X418748Y294943D01*
X418480Y295098D01*
X418173Y295150D01*
X417790Y295047D01*
X417522Y294788D01*
X417445Y294478D01*
X417483Y294168D01*
X417637Y293910D01*
X418403Y293393D01*
X418748Y293032D01*
X418978Y292515D01*
X419055Y292050D01*
X417445D01*
G01X414690D02*
Y295150D01*
X416108Y292928D01*
X414192D01*
G01X412050Y292050D02*
Y295150D01*
X412510Y294530D01*
G01Y292050D02*
X411590D01*
G01X399808Y341193D02*
X399963Y340963D01*
X400066Y340695D01*
Y340388D01*
X399911Y340043D01*
X399653Y339775D01*
X399343Y339583D01*
X398826Y339430D01*
X398361Y339392D01*
X397896Y339468D01*
X397586Y339583D01*
X397276Y339813D01*
X397069Y340082D01*
X396966Y340350D01*
Y340618D01*
X397069Y340887D01*
X397224Y341117D01*
X397431Y341308D01*
G01X396966Y343450D02*
X400066D01*
X399446Y342990D01*
G01X396966D02*
Y343910D01*
G01X399549Y345822D02*
X399859Y346052D01*
X400014Y346320D01*
X400066Y346627D01*
X399963Y347010D01*
X399704Y347278D01*
X399394Y347355D01*
X399084Y347317D01*
X398826Y347163D01*
X398309Y346397D01*
X397948Y346052D01*
X397431Y345822D01*
X396966Y345745D01*
Y347355D01*
G01X397586Y348807D02*
X397224Y349037D01*
X397018Y349343D01*
X396966Y349688D01*
X397018Y349995D01*
X397276Y350302D01*
X397586Y350493D01*
X397896Y350532D01*
X398258Y350455D01*
X398516Y350187D01*
X398619Y349918D01*
Y349573D01*
G01Y349918D02*
X398774Y350148D01*
X399033Y350340D01*
X399343Y350417D01*
X399653Y350340D01*
X399911Y350148D01*
X400066Y349803D01*
X400014Y349458D01*
X399808Y349113D01*
G01X432807Y74292D02*
X433037Y74447D01*
X433305Y74550D01*
X433612D01*
X433957Y74395D01*
X434225Y74137D01*
X434417Y73827D01*
X434570Y73310D01*
X434608Y72845D01*
X434532Y72380D01*
X434417Y72070D01*
X434187Y71760D01*
X433918Y71553D01*
X433650Y71450D01*
X433382D01*
X433113Y71553D01*
X432883Y71708D01*
X432692Y71915D01*
G01X431278Y74033D02*
X431048Y74343D01*
X430780Y74498D01*
X430473Y74550D01*
X430090Y74447D01*
X429822Y74188D01*
X429745Y73878D01*
X429783Y73568D01*
X429937Y73310D01*
X430703Y72793D01*
X431048Y72432D01*
X431278Y71915D01*
X431355Y71450D01*
X429745D01*
G01X426990D02*
Y74550D01*
X428408Y72328D01*
X426492D01*
G01X423890Y71450D02*
Y74550D01*
X425308Y72328D01*
X423392D01*
G01X429066Y76633D02*
X425966D01*
Y78167D01*
G01Y80500D02*
X429066D01*
X428446Y80040D01*
G01X425966D02*
Y80960D01*
G01Y84060D02*
X429066D01*
X426844Y82642D01*
Y84558D01*
G01X428792Y90193D02*
X428947Y89963D01*
X429050Y89695D01*
Y89388D01*
X428895Y89043D01*
X428637Y88775D01*
X428327Y88583D01*
X427810Y88430D01*
X427345Y88392D01*
X426880Y88468D01*
X426570Y88583D01*
X426260Y88813D01*
X426053Y89082D01*
X425950Y89350D01*
Y89618D01*
X426053Y89887D01*
X426208Y90117D01*
X426415Y90308D01*
G01X428533Y91722D02*
X428843Y91952D01*
X428998Y92220D01*
X429050Y92527D01*
X428947Y92910D01*
X428688Y93178D01*
X428378Y93255D01*
X428068Y93217D01*
X427810Y93063D01*
X427293Y92297D01*
X426932Y91952D01*
X426415Y91722D01*
X425950Y91645D01*
Y93255D01*
G01Y96010D02*
X429050D01*
X426828Y94592D01*
Y96508D01*
G01X427242Y97922D02*
X427603Y98190D01*
X427810Y98420D01*
X427913Y98727D01*
X427810Y98995D01*
X427603Y99187D01*
X427293Y99340D01*
X426932Y99378D01*
X426622Y99340D01*
X426312Y99187D01*
X426053Y98957D01*
X425950Y98688D01*
X426053Y98382D01*
X426363Y98113D01*
X426828Y97960D01*
X427345Y97922D01*
X428017Y97998D01*
X428378Y98113D01*
X428740Y98305D01*
X428998Y98573D01*
X429050Y98842D01*
X428947Y99110D01*
X428688Y99302D01*
G01X431292Y142287D02*
X431417Y142127D01*
X431500Y141940D01*
Y141727D01*
X431375Y141487D01*
X431167Y141300D01*
X430917Y141167D01*
X430500Y141060D01*
X430125Y141033D01*
X429750Y141087D01*
X429500Y141167D01*
X429250Y141327D01*
X429083Y141513D01*
X429000Y141700D01*
Y141887D01*
X429083Y142073D01*
X429208Y142233D01*
X429375Y142367D01*
G01X429000Y143900D02*
X431500D01*
X431000Y143580D01*
G01X429000D02*
Y144220D01*
G01Y146420D02*
X431500D01*
X429708Y145433D01*
Y146767D01*
G01X431083Y147793D02*
X431333Y147953D01*
X431458Y148140D01*
X431500Y148353D01*
X431417Y148620D01*
X431208Y148807D01*
X430958Y148860D01*
X430708Y148833D01*
X430500Y148727D01*
X430083Y148193D01*
X429792Y147953D01*
X429375Y147793D01*
X429000Y147740D01*
Y148860D01*
G01X421292Y136787D02*
X421417Y136627D01*
X421500Y136440D01*
Y136227D01*
X421375Y135987D01*
X421167Y135800D01*
X420917Y135667D01*
X420500Y135560D01*
X420125Y135533D01*
X419750Y135587D01*
X419500Y135667D01*
X419250Y135827D01*
X419083Y136013D01*
X419000Y136200D01*
Y136387D01*
X419083Y136573D01*
X419208Y136733D01*
X419375Y136867D01*
G01X421083Y137893D02*
X421333Y138053D01*
X421458Y138240D01*
X421500Y138453D01*
X421417Y138720D01*
X421208Y138907D01*
X420958Y138960D01*
X420708Y138933D01*
X420500Y138827D01*
X420083Y138293D01*
X419792Y138053D01*
X419375Y137893D01*
X419000Y137840D01*
Y138960D01*
G01X421500Y140600D02*
X421417Y140387D01*
X421208Y140227D01*
X420958Y140120D01*
X420625Y140040D01*
X420250Y140013D01*
X419875Y140040D01*
X419542Y140120D01*
X419292Y140227D01*
X419083Y140387D01*
X419000Y140600D01*
X419083Y140813D01*
X419292Y140973D01*
X419542Y141080D01*
X419875Y141160D01*
X420250Y141187D01*
X420625Y141160D01*
X420958Y141080D01*
X421208Y140973D01*
X421417Y140813D01*
X421500Y140600D01*
G01X419000Y142800D02*
X419042Y142987D01*
X419167Y143200D01*
X419375Y143333D01*
X419667Y143387D01*
X419958Y143333D01*
X420208Y143173D01*
X420333Y142933D01*
Y142667D01*
X420417Y142507D01*
X420625Y142373D01*
X420917Y142320D01*
X421208Y142400D01*
X421417Y142587D01*
X421500Y142800D01*
X421417Y143013D01*
X421208Y143200D01*
X420917Y143280D01*
X420625Y143227D01*
X420417Y143093D01*
X420333Y142933D01*
Y142667D01*
X420208Y142427D01*
X419958Y142267D01*
X419667Y142213D01*
X419375Y142267D01*
X419167Y142400D01*
X419042Y142613D01*
X419000Y142800D01*
G01X431242Y164287D02*
X431367Y164127D01*
X431450Y163940D01*
Y163727D01*
X431325Y163487D01*
X431117Y163300D01*
X430867Y163167D01*
X430450Y163060D01*
X430075Y163033D01*
X429700Y163087D01*
X429450Y163167D01*
X429200Y163327D01*
X429033Y163513D01*
X428950Y163700D01*
Y163887D01*
X429033Y164073D01*
X429158Y164233D01*
X429325Y164367D01*
G01X428950Y165900D02*
X431450D01*
X430950Y165580D01*
G01X428950D02*
Y166220D01*
G01Y168100D02*
X431450D01*
X430950Y167780D01*
G01X428950D02*
Y168420D01*
G01Y170620D02*
X431450D01*
X429658Y169633D01*
Y170967D01*
G01X431292Y153287D02*
X431417Y153127D01*
X431500Y152940D01*
Y152727D01*
X431375Y152487D01*
X431167Y152300D01*
X430917Y152167D01*
X430500Y152060D01*
X430125Y152033D01*
X429750Y152087D01*
X429500Y152167D01*
X429250Y152327D01*
X429083Y152513D01*
X429000Y152700D01*
Y152887D01*
X429083Y153073D01*
X429208Y153233D01*
X429375Y153367D01*
G01X429000Y154900D02*
X431500D01*
X431000Y154580D01*
G01X429000D02*
Y155220D01*
G01X429500Y156513D02*
X429208Y156673D01*
X429042Y156887D01*
X429000Y157127D01*
X429042Y157340D01*
X429250Y157553D01*
X429500Y157687D01*
X429750Y157713D01*
X430042Y157660D01*
X430250Y157473D01*
X430333Y157287D01*
Y157047D01*
G01Y157287D02*
X430458Y157447D01*
X430667Y157580D01*
X430917Y157633D01*
X431167Y157580D01*
X431375Y157447D01*
X431500Y157207D01*
X431458Y156967D01*
X431292Y156727D01*
G01X429500Y158713D02*
X429208Y158873D01*
X429042Y159087D01*
X429000Y159327D01*
X429042Y159540D01*
X429250Y159753D01*
X429500Y159887D01*
X429750Y159913D01*
X430042Y159860D01*
X430250Y159673D01*
X430333Y159487D01*
Y159247D01*
G01Y159487D02*
X430458Y159647D01*
X430667Y159780D01*
X430917Y159833D01*
X431167Y159780D01*
X431375Y159647D01*
X431500Y159407D01*
X431458Y159167D01*
X431292Y158927D01*
G01X421400Y160476D02*
X421525Y160316D01*
X421608Y160129D01*
Y159916D01*
X421483Y159676D01*
X421275Y159489D01*
X421025Y159356D01*
X420608Y159249D01*
X420233Y159222D01*
X419858Y159276D01*
X419608Y159356D01*
X419358Y159516D01*
X419191Y159702D01*
X419108Y159889D01*
Y160076D01*
X419191Y160262D01*
X419316Y160422D01*
X419483Y160556D01*
G01X419108Y162089D02*
X421608D01*
X421108Y161769D01*
G01X419108D02*
Y162409D01*
G01X421191Y163782D02*
X421441Y163942D01*
X421566Y164129D01*
X421608Y164342D01*
X421525Y164609D01*
X421316Y164796D01*
X421066Y164849D01*
X420816Y164822D01*
X420608Y164716D01*
X420191Y164182D01*
X419900Y163942D01*
X419483Y163782D01*
X419108Y163729D01*
Y164849D01*
G01X421608Y166489D02*
X421525Y166276D01*
X421316Y166116D01*
X421066Y166009D01*
X420733Y165929D01*
X420358Y165902D01*
X419983Y165929D01*
X419650Y166009D01*
X419400Y166116D01*
X419191Y166276D01*
X419108Y166489D01*
X419191Y166702D01*
X419400Y166862D01*
X419650Y166969D01*
X419983Y167049D01*
X420358Y167076D01*
X420733Y167049D01*
X421066Y166969D01*
X421316Y166862D01*
X421525Y166702D01*
X421608Y166489D01*
G01X422042Y148287D02*
X422167Y148127D01*
X422250Y147940D01*
Y147727D01*
X422125Y147487D01*
X421917Y147300D01*
X421667Y147167D01*
X421250Y147060D01*
X420875Y147033D01*
X420500Y147087D01*
X420250Y147167D01*
X420000Y147327D01*
X419833Y147513D01*
X419750Y147700D01*
Y147887D01*
X419833Y148073D01*
X419958Y148233D01*
X420125Y148367D01*
G01X419750Y149900D02*
X422250D01*
X421750Y149580D01*
G01X419750D02*
Y150220D01*
G01X420792Y151593D02*
X421083Y151780D01*
X421250Y151940D01*
X421333Y152153D01*
X421250Y152340D01*
X421083Y152473D01*
X420833Y152580D01*
X420542Y152607D01*
X420292Y152580D01*
X420042Y152473D01*
X419833Y152313D01*
X419750Y152127D01*
X419833Y151913D01*
X420083Y151727D01*
X420458Y151620D01*
X420875Y151593D01*
X421417Y151647D01*
X421708Y151727D01*
X422000Y151860D01*
X422208Y152047D01*
X422250Y152233D01*
X422167Y152420D01*
X421958Y152553D01*
G01X420042Y153847D02*
X419833Y154033D01*
X419750Y154247D01*
X419833Y154460D01*
X420083Y154647D01*
X420458Y154780D01*
X420833Y154833D01*
X421292D01*
X421667Y154780D01*
X422000Y154647D01*
X422167Y154487D01*
X422250Y154300D01*
X422167Y154087D01*
X422000Y153927D01*
X421750Y153820D01*
X421417Y153767D01*
X421125Y153820D01*
X420833Y153953D01*
X420667Y154113D01*
X420625Y154300D01*
X420708Y154513D01*
X420917Y154673D01*
X421292Y154833D01*
G01X425335Y160477D02*
X425460Y160317D01*
X425543Y160130D01*
Y159917D01*
X425418Y159677D01*
X425210Y159490D01*
X424960Y159357D01*
X424543Y159250D01*
X424168Y159223D01*
X423793Y159277D01*
X423543Y159357D01*
X423293Y159517D01*
X423126Y159703D01*
X423043Y159890D01*
Y160077D01*
X423126Y160263D01*
X423251Y160423D01*
X423418Y160557D01*
G01X423043Y162090D02*
X425543D01*
X425043Y161770D01*
G01X423043D02*
Y162410D01*
G01X424085Y163783D02*
X424376Y163970D01*
X424543Y164130D01*
X424626Y164343D01*
X424543Y164530D01*
X424376Y164663D01*
X424126Y164770D01*
X423835Y164797D01*
X423585Y164770D01*
X423335Y164663D01*
X423126Y164503D01*
X423043Y164317D01*
X423126Y164103D01*
X423376Y163917D01*
X423751Y163810D01*
X424168Y163783D01*
X424710Y163837D01*
X425001Y163917D01*
X425293Y164050D01*
X425501Y164237D01*
X425543Y164423D01*
X425460Y164610D01*
X425251Y164743D01*
G01X424085Y165983D02*
X424376Y166170D01*
X424543Y166330D01*
X424626Y166543D01*
X424543Y166730D01*
X424376Y166863D01*
X424126Y166970D01*
X423835Y166997D01*
X423585Y166970D01*
X423335Y166863D01*
X423126Y166703D01*
X423043Y166517D01*
X423126Y166303D01*
X423376Y166117D01*
X423751Y166010D01*
X424168Y165983D01*
X424710Y166037D01*
X425001Y166117D01*
X425293Y166250D01*
X425501Y166437D01*
X425543Y166623D01*
X425460Y166810D01*
X425251Y166943D01*
G01X417963Y164914D02*
X418088Y164754D01*
X418171Y164567D01*
Y164354D01*
X418046Y164114D01*
X417838Y163927D01*
X417588Y163794D01*
X417171Y163687D01*
X416796Y163660D01*
X416421Y163714D01*
X416171Y163794D01*
X415921Y163954D01*
X415754Y164140D01*
X415671Y164327D01*
Y164514D01*
X415754Y164700D01*
X415879Y164860D01*
X416046Y164994D01*
G01X415671Y166527D02*
X418171D01*
X417671Y166207D01*
G01X415671D02*
Y166847D01*
G01X416046Y168140D02*
X415838Y168300D01*
X415713Y168487D01*
X415671Y168727D01*
X415754Y168967D01*
X415921Y169154D01*
X416213Y169287D01*
X416546Y169314D01*
X416879Y169260D01*
X417088Y169127D01*
X417254Y168940D01*
X417296Y168754D01*
X417254Y168567D01*
X417088Y168327D01*
X418171Y168407D01*
Y169127D01*
G01X416713Y170420D02*
X417004Y170607D01*
X417171Y170767D01*
X417254Y170980D01*
X417171Y171167D01*
X417004Y171300D01*
X416754Y171407D01*
X416463Y171434D01*
X416213Y171407D01*
X415963Y171300D01*
X415754Y171140D01*
X415671Y170954D01*
X415754Y170740D01*
X416004Y170554D01*
X416379Y170447D01*
X416796Y170420D01*
X417338Y170474D01*
X417629Y170554D01*
X417921Y170687D01*
X418129Y170874D01*
X418171Y171060D01*
X418088Y171247D01*
X417879Y171380D01*
G01X425213Y158292D02*
X425373Y158417D01*
X425560Y158500D01*
X425773D01*
X426013Y158375D01*
X426200Y158167D01*
X426333Y157917D01*
X426440Y157500D01*
X426467Y157125D01*
X426413Y156750D01*
X426333Y156500D01*
X426173Y156250D01*
X425987Y156083D01*
X425800Y156000D01*
X425613D01*
X425427Y156083D01*
X425267Y156208D01*
X425133Y156375D01*
G01X423600Y156000D02*
Y158500D01*
X423920Y158000D01*
G01Y156000D02*
X423280D01*
G01X421080D02*
Y158500D01*
X422067Y156708D01*
X420733D01*
G01X419200Y156000D02*
Y158500D01*
X419520Y158000D01*
G01Y156000D02*
X418880D01*
G01X417463Y156039D02*
X417588Y155879D01*
X417671Y155692D01*
Y155479D01*
X417546Y155239D01*
X417338Y155052D01*
X417088Y154919D01*
X416671Y154812D01*
X416296Y154785D01*
X415921Y154839D01*
X415671Y154919D01*
X415421Y155079D01*
X415254Y155265D01*
X415171Y155452D01*
Y155639D01*
X415254Y155825D01*
X415379Y155985D01*
X415546Y156119D01*
G01X415171Y157652D02*
X417671D01*
X417171Y157332D01*
G01X415171D02*
Y157972D01*
G01X417254Y159345D02*
X417504Y159505D01*
X417629Y159692D01*
X417671Y159905D01*
X417588Y160172D01*
X417379Y160359D01*
X417129Y160412D01*
X416879Y160385D01*
X416671Y160279D01*
X416254Y159745D01*
X415963Y159505D01*
X415546Y159345D01*
X415171Y159292D01*
Y160412D01*
G01Y162052D02*
X417671D01*
X417171Y161732D01*
G01X415171D02*
Y162372D01*
G01X431342Y178887D02*
X431467Y178727D01*
X431550Y178540D01*
Y178327D01*
X431425Y178087D01*
X431217Y177900D01*
X430967Y177767D01*
X430550Y177660D01*
X430175Y177633D01*
X429800Y177687D01*
X429550Y177767D01*
X429300Y177927D01*
X429133Y178113D01*
X429050Y178300D01*
Y178487D01*
X429133Y178673D01*
X429258Y178833D01*
X429425Y178967D01*
G01X429050Y180500D02*
X431550D01*
X431050Y180180D01*
G01X429050D02*
Y180820D01*
G01Y182700D02*
X431550D01*
X431050Y182380D01*
G01X429050D02*
Y183020D01*
G01X429425Y184313D02*
X429217Y184473D01*
X429092Y184660D01*
X429050Y184900D01*
X429133Y185140D01*
X429300Y185327D01*
X429592Y185460D01*
X429925Y185487D01*
X430258Y185433D01*
X430467Y185300D01*
X430633Y185113D01*
X430675Y184927D01*
X430633Y184740D01*
X430467Y184500D01*
X431550Y184580D01*
Y185300D01*
G01X424713Y175742D02*
X424873Y175867D01*
X425060Y175950D01*
X425273D01*
X425513Y175825D01*
X425700Y175617D01*
X425833Y175367D01*
X425940Y174950D01*
X425967Y174575D01*
X425913Y174200D01*
X425833Y173950D01*
X425673Y173700D01*
X425487Y173533D01*
X425300Y173450D01*
X425113D01*
X424927Y173533D01*
X424767Y173658D01*
X424633Y173825D01*
G01X423607Y175533D02*
X423447Y175783D01*
X423260Y175908D01*
X423047Y175950D01*
X422780Y175867D01*
X422593Y175658D01*
X422540Y175408D01*
X422567Y175158D01*
X422673Y174950D01*
X423207Y174533D01*
X423447Y174242D01*
X423607Y173825D01*
X423660Y173450D01*
X422540D01*
G01X420900D02*
Y175950D01*
X421220Y175450D01*
G01Y173450D02*
X420580D01*
G01X419153Y173742D02*
X418967Y173533D01*
X418753Y173450D01*
X418540Y173533D01*
X418353Y173783D01*
X418220Y174158D01*
X418167Y174533D01*
Y174992D01*
X418220Y175367D01*
X418353Y175700D01*
X418513Y175867D01*
X418700Y175950D01*
X418913Y175867D01*
X419073Y175700D01*
X419180Y175450D01*
X419233Y175117D01*
X419180Y174825D01*
X419047Y174533D01*
X418887Y174367D01*
X418700Y174325D01*
X418487Y174408D01*
X418327Y174617D01*
X418167Y174992D01*
G01X425339Y181148D02*
X425499Y181273D01*
X425686Y181356D01*
X425899D01*
X426139Y181231D01*
X426326Y181023D01*
X426459Y180773D01*
X426566Y180356D01*
X426593Y179981D01*
X426539Y179606D01*
X426459Y179356D01*
X426299Y179106D01*
X426113Y178939D01*
X425926Y178856D01*
X425739D01*
X425553Y178939D01*
X425393Y179064D01*
X425259Y179231D01*
G01X424233Y180939D02*
X424073Y181189D01*
X423886Y181314D01*
X423673Y181356D01*
X423406Y181273D01*
X423219Y181064D01*
X423166Y180814D01*
X423193Y180564D01*
X423299Y180356D01*
X423833Y179939D01*
X424073Y179648D01*
X424233Y179231D01*
X424286Y178856D01*
X423166D01*
G01X421526Y181356D02*
X421739Y181273D01*
X421899Y181064D01*
X422006Y180814D01*
X422086Y180481D01*
X422113Y180106D01*
X422086Y179731D01*
X422006Y179398D01*
X421899Y179148D01*
X421739Y178939D01*
X421526Y178856D01*
X421313Y178939D01*
X421153Y179148D01*
X421046Y179398D01*
X420966Y179731D01*
X420939Y180106D01*
X420966Y180481D01*
X421046Y180814D01*
X421153Y181064D01*
X421313Y181273D01*
X421526Y181356D01*
G01X419326D02*
X419539Y181273D01*
X419699Y181064D01*
X419806Y180814D01*
X419886Y180481D01*
X419913Y180106D01*
X419886Y179731D01*
X419806Y179398D01*
X419699Y179148D01*
X419539Y178939D01*
X419326Y178856D01*
X419113Y178939D01*
X418953Y179148D01*
X418846Y179398D01*
X418766Y179731D01*
X418739Y180106D01*
X418766Y180481D01*
X418846Y180814D01*
X418953Y181064D01*
X419113Y181273D01*
X419326Y181356D01*
G01X425713Y170292D02*
X425873Y170417D01*
X426060Y170500D01*
X426273D01*
X426513Y170375D01*
X426700Y170167D01*
X426833Y169917D01*
X426940Y169500D01*
X426967Y169125D01*
X426913Y168750D01*
X426833Y168500D01*
X426673Y168250D01*
X426487Y168083D01*
X426300Y168000D01*
X426113D01*
X425927Y168083D01*
X425767Y168208D01*
X425633Y168375D01*
G01X424100Y168000D02*
Y170500D01*
X424420Y170000D01*
G01Y168000D02*
X423780D01*
G01X421900Y170500D02*
X422113Y170417D01*
X422273Y170208D01*
X422380Y169958D01*
X422460Y169625D01*
X422487Y169250D01*
X422460Y168875D01*
X422380Y168542D01*
X422273Y168292D01*
X422113Y168083D01*
X421900Y168000D01*
X421687Y168083D01*
X421527Y168292D01*
X421420Y168542D01*
X421340Y168875D01*
X421313Y169250D01*
X421340Y169625D01*
X421420Y169958D01*
X421527Y170208D01*
X421687Y170417D01*
X421900Y170500D01*
G01X420153Y168292D02*
X419967Y168083D01*
X419753Y168000D01*
X419540Y168083D01*
X419353Y168333D01*
X419220Y168708D01*
X419167Y169083D01*
Y169542D01*
X419220Y169917D01*
X419353Y170250D01*
X419513Y170417D01*
X419700Y170500D01*
X419913Y170417D01*
X420073Y170250D01*
X420180Y170000D01*
X420233Y169667D01*
X420180Y169375D01*
X420047Y169083D01*
X419887Y168917D01*
X419700Y168875D01*
X419487Y168958D01*
X419327Y169167D01*
X419167Y169542D01*
G01X421792Y186287D02*
X421917Y186127D01*
X422000Y185940D01*
Y185727D01*
X421875Y185487D01*
X421667Y185300D01*
X421417Y185167D01*
X421000Y185060D01*
X420625Y185033D01*
X420250Y185087D01*
X420000Y185167D01*
X419750Y185327D01*
X419583Y185513D01*
X419500Y185700D01*
Y185887D01*
X419583Y186073D01*
X419708Y186233D01*
X419875Y186367D01*
G01X421583Y187393D02*
X421833Y187553D01*
X421958Y187740D01*
X422000Y187953D01*
X421917Y188220D01*
X421708Y188407D01*
X421458Y188460D01*
X421208Y188433D01*
X421000Y188327D01*
X420583Y187793D01*
X420292Y187553D01*
X419875Y187393D01*
X419500Y187340D01*
Y188460D01*
G01X421583Y189593D02*
X421833Y189753D01*
X421958Y189940D01*
X422000Y190153D01*
X421917Y190420D01*
X421708Y190607D01*
X421458Y190660D01*
X421208Y190633D01*
X421000Y190527D01*
X420583Y189993D01*
X420292Y189753D01*
X419875Y189593D01*
X419500Y189540D01*
Y190660D01*
G01Y192300D02*
X422000D01*
X421500Y191980D01*
G01X419500D02*
Y192620D01*
G01X431292Y189787D02*
X431417Y189627D01*
X431500Y189440D01*
Y189227D01*
X431375Y188987D01*
X431167Y188800D01*
X430917Y188667D01*
X430500Y188560D01*
X430125Y188533D01*
X429750Y188587D01*
X429500Y188667D01*
X429250Y188827D01*
X429083Y189013D01*
X429000Y189200D01*
Y189387D01*
X429083Y189573D01*
X429208Y189733D01*
X429375Y189867D01*
G01X429000Y191400D02*
X431500D01*
X431000Y191080D01*
G01X429000D02*
Y191720D01*
G01Y193920D02*
X431500D01*
X429708Y192933D01*
Y194267D01*
G01X429000Y196120D02*
X431500D01*
X429708Y195133D01*
Y196467D01*
G01X418292Y194787D02*
X418417Y194627D01*
X418500Y194440D01*
Y194227D01*
X418375Y193987D01*
X418167Y193800D01*
X417917Y193667D01*
X417500Y193560D01*
X417125Y193533D01*
X416750Y193587D01*
X416500Y193667D01*
X416250Y193827D01*
X416083Y194013D01*
X416000Y194200D01*
Y194387D01*
X416083Y194573D01*
X416208Y194733D01*
X416375Y194867D01*
G01X416000Y196400D02*
X418500D01*
X418000Y196080D01*
G01X416000D02*
Y196720D01*
G01Y198600D02*
X418500D01*
X418000Y198280D01*
G01X416000D02*
Y198920D01*
G01X416292Y200347D02*
X416083Y200533D01*
X416000Y200747D01*
X416083Y200960D01*
X416333Y201147D01*
X416708Y201280D01*
X417083Y201333D01*
X417542D01*
X417917Y201280D01*
X418250Y201147D01*
X418417Y200987D01*
X418500Y200800D01*
X418417Y200587D01*
X418250Y200427D01*
X418000Y200320D01*
X417667Y200267D01*
X417375Y200320D01*
X417083Y200453D01*
X416917Y200613D01*
X416875Y200800D01*
X416958Y201013D01*
X417167Y201173D01*
X417542Y201333D01*
G01X430792Y201787D02*
X430917Y201627D01*
X431000Y201440D01*
Y201227D01*
X430875Y200987D01*
X430667Y200800D01*
X430417Y200667D01*
X430000Y200560D01*
X429625Y200533D01*
X429250Y200587D01*
X429000Y200667D01*
X428750Y200827D01*
X428583Y201013D01*
X428500Y201200D01*
Y201387D01*
X428583Y201573D01*
X428708Y201733D01*
X428875Y201867D01*
G01X428500Y203400D02*
X431000D01*
X430500Y203080D01*
G01X428500D02*
Y203720D01*
G01Y205920D02*
X431000D01*
X429208Y204933D01*
Y206267D01*
G01X428792Y207347D02*
X428583Y207533D01*
X428500Y207747D01*
X428583Y207960D01*
X428833Y208147D01*
X429208Y208280D01*
X429583Y208333D01*
X430042D01*
X430417Y208280D01*
X430750Y208147D01*
X430917Y207987D01*
X431000Y207800D01*
X430917Y207587D01*
X430750Y207427D01*
X430500Y207320D01*
X430167Y207267D01*
X429875Y207320D01*
X429583Y207453D01*
X429417Y207613D01*
X429375Y207800D01*
X429458Y208013D01*
X429667Y208173D01*
X430042Y208333D01*
G01X425885Y210064D02*
X426040Y209834D01*
X426143Y209566D01*
Y209259D01*
X425988Y208914D01*
X425730Y208646D01*
X425420Y208454D01*
X424903Y208301D01*
X424438Y208263D01*
X423973Y208339D01*
X423663Y208454D01*
X423353Y208684D01*
X423146Y208953D01*
X423043Y209221D01*
Y209489D01*
X423146Y209758D01*
X423301Y209988D01*
X423508Y210179D01*
G01X423043Y212321D02*
X426143D01*
X425523Y211861D01*
G01X423043D02*
Y212781D01*
G01X424335Y214693D02*
X424696Y214961D01*
X424903Y215191D01*
X425006Y215498D01*
X424903Y215766D01*
X424696Y215958D01*
X424386Y216111D01*
X424025Y216149D01*
X423715Y216111D01*
X423405Y215958D01*
X423146Y215728D01*
X423043Y215459D01*
X423146Y215153D01*
X423456Y214884D01*
X423921Y214731D01*
X424438Y214693D01*
X425110Y214769D01*
X425471Y214884D01*
X425833Y215076D01*
X426091Y215344D01*
X426143Y215613D01*
X426040Y215881D01*
X425781Y216073D01*
G01X425626Y217793D02*
X425936Y218023D01*
X426091Y218291D01*
X426143Y218598D01*
X426040Y218981D01*
X425781Y219249D01*
X425471Y219326D01*
X425161Y219288D01*
X424903Y219134D01*
X424386Y218368D01*
X424025Y218023D01*
X423508Y217793D01*
X423043Y217716D01*
Y219326D01*
G01X419866Y247683D02*
X422966D01*
Y248642D01*
X422811Y248948D01*
X422604Y249140D01*
X422191Y249217D01*
X421778Y249140D01*
X421519Y248910D01*
X421364Y248642D01*
Y247683D01*
G01Y248642D02*
X419866Y249217D01*
G01X420486Y250707D02*
X420124Y250937D01*
X419918Y251243D01*
X419866Y251588D01*
X419918Y251895D01*
X420176Y252202D01*
X420486Y252393D01*
X420796Y252432D01*
X421158Y252355D01*
X421416Y252087D01*
X421519Y251818D01*
Y251473D01*
G01Y251818D02*
X421674Y252048D01*
X421933Y252240D01*
X422243Y252317D01*
X422553Y252240D01*
X422811Y252048D01*
X422966Y251703D01*
X422914Y251358D01*
X422708Y251013D01*
G01X422449Y253922D02*
X422759Y254152D01*
X422914Y254420D01*
X422966Y254727D01*
X422863Y255110D01*
X422604Y255378D01*
X422294Y255455D01*
X421984Y255417D01*
X421726Y255263D01*
X421209Y254497D01*
X420848Y254152D01*
X420331Y253922D01*
X419866Y253845D01*
Y255455D01*
G01X421158Y257022D02*
X421519Y257290D01*
X421726Y257520D01*
X421829Y257827D01*
X421726Y258095D01*
X421519Y258287D01*
X421209Y258440D01*
X420848Y258478D01*
X420538Y258440D01*
X420228Y258287D01*
X419969Y258057D01*
X419866Y257788D01*
X419969Y257482D01*
X420279Y257213D01*
X420744Y257060D01*
X421261Y257022D01*
X421933Y257098D01*
X422294Y257213D01*
X422656Y257405D01*
X422914Y257673D01*
X422966Y257942D01*
X422863Y258210D01*
X422604Y258402D01*
G01X413966Y247683D02*
X417066D01*
Y248642D01*
X416911Y248948D01*
X416704Y249140D01*
X416291Y249217D01*
X415878Y249140D01*
X415619Y248910D01*
X415464Y248642D01*
Y247683D01*
G01Y248642D02*
X413966Y249217D01*
G01X414586Y250707D02*
X414224Y250937D01*
X414018Y251243D01*
X413966Y251588D01*
X414018Y251895D01*
X414276Y252202D01*
X414586Y252393D01*
X414896Y252432D01*
X415258Y252355D01*
X415516Y252087D01*
X415619Y251818D01*
Y251473D01*
G01Y251818D02*
X415774Y252048D01*
X416033Y252240D01*
X416343Y252317D01*
X416653Y252240D01*
X416911Y252048D01*
X417066Y251703D01*
X417014Y251358D01*
X416808Y251013D01*
G01X416549Y253922D02*
X416859Y254152D01*
X417014Y254420D01*
X417066Y254727D01*
X416963Y255110D01*
X416704Y255378D01*
X416394Y255455D01*
X416084Y255417D01*
X415826Y255263D01*
X415309Y254497D01*
X414948Y254152D01*
X414431Y253922D01*
X413966Y253845D01*
Y255455D01*
G01Y257750D02*
X414018Y258018D01*
X414173Y258325D01*
X414431Y258517D01*
X414793Y258593D01*
X415154Y258517D01*
X415464Y258287D01*
X415619Y257942D01*
Y257558D01*
X415723Y257328D01*
X415981Y257137D01*
X416343Y257060D01*
X416704Y257175D01*
X416963Y257443D01*
X417066Y257750D01*
X416963Y258057D01*
X416704Y258325D01*
X416343Y258440D01*
X415981Y258363D01*
X415723Y258172D01*
X415619Y257942D01*
Y257558D01*
X415464Y257213D01*
X415154Y256983D01*
X414793Y256907D01*
X414431Y256983D01*
X414173Y257175D01*
X414018Y257482D01*
X413966Y257750D01*
G01X418808Y341193D02*
X418963Y340963D01*
X419066Y340695D01*
Y340388D01*
X418911Y340043D01*
X418653Y339775D01*
X418343Y339583D01*
X417826Y339430D01*
X417361Y339392D01*
X416896Y339468D01*
X416586Y339583D01*
X416276Y339813D01*
X416069Y340082D01*
X415966Y340350D01*
Y340618D01*
X416069Y340887D01*
X416224Y341117D01*
X416431Y341308D01*
G01X415966Y343450D02*
X419066D01*
X418446Y342990D01*
G01X415966D02*
Y343910D01*
G01X419066Y346550D02*
X418963Y346243D01*
X418704Y346013D01*
X418394Y345860D01*
X417981Y345745D01*
X417516Y345707D01*
X417051Y345745D01*
X416638Y345860D01*
X416328Y346013D01*
X416069Y346243D01*
X415966Y346550D01*
X416069Y346857D01*
X416328Y347087D01*
X416638Y347240D01*
X417051Y347355D01*
X417516Y347393D01*
X417981Y347355D01*
X418394Y347240D01*
X418704Y347087D01*
X418963Y346857D01*
X419066Y346550D01*
G01X418549Y348922D02*
X418859Y349152D01*
X419014Y349420D01*
X419066Y349727D01*
X418963Y350110D01*
X418704Y350378D01*
X418394Y350455D01*
X418084Y350417D01*
X417826Y350263D01*
X417309Y349497D01*
X416948Y349152D01*
X416431Y348922D01*
X415966Y348845D01*
Y350455D01*
G01X425292Y392393D02*
X425447Y392163D01*
X425550Y391895D01*
Y391588D01*
X425395Y391243D01*
X425137Y390975D01*
X424827Y390783D01*
X424310Y390630D01*
X423845Y390592D01*
X423380Y390668D01*
X423070Y390783D01*
X422760Y391013D01*
X422553Y391282D01*
X422450Y391550D01*
Y391818D01*
X422553Y392087D01*
X422708Y392317D01*
X422915Y392508D01*
G01X423070Y393807D02*
X422708Y394037D01*
X422502Y394343D01*
X422450Y394688D01*
X422502Y394995D01*
X422760Y395302D01*
X423070Y395493D01*
X423380Y395532D01*
X423742Y395455D01*
X424000Y395187D01*
X424103Y394918D01*
Y394573D01*
G01Y394918D02*
X424258Y395148D01*
X424517Y395340D01*
X424827Y395417D01*
X425137Y395340D01*
X425395Y395148D01*
X425550Y394803D01*
X425498Y394458D01*
X425292Y394113D01*
G01X422450Y397750D02*
X425550D01*
X424930Y397290D01*
G01X422450D02*
Y398210D01*
G01X423742Y400122D02*
X424103Y400390D01*
X424310Y400620D01*
X424413Y400927D01*
X424310Y401195D01*
X424103Y401387D01*
X423793Y401540D01*
X423432Y401578D01*
X423122Y401540D01*
X422812Y401387D01*
X422553Y401157D01*
X422450Y400888D01*
X422553Y400582D01*
X422863Y400313D01*
X423328Y400160D01*
X423845Y400122D01*
X424517Y400198D01*
X424878Y400313D01*
X425240Y400505D01*
X425498Y400773D01*
X425550Y401042D01*
X425447Y401310D01*
X425188Y401502D01*
G01X429917Y404950D02*
Y408050D01*
X428958D01*
X428652Y407895D01*
X428460Y407688D01*
X428383Y407275D01*
X428460Y406862D01*
X428690Y406603D01*
X428958Y406448D01*
X429917D01*
G01X428958D02*
X428383Y404950D01*
G01X426893Y405570D02*
X426663Y405208D01*
X426357Y405002D01*
X426012Y404950D01*
X425705Y405002D01*
X425398Y405260D01*
X425207Y405570D01*
X425168Y405880D01*
X425245Y406242D01*
X425513Y406500D01*
X425782Y406603D01*
X426127D01*
G01X425782D02*
X425552Y406758D01*
X425360Y407017D01*
X425283Y407327D01*
X425360Y407637D01*
X425552Y407895D01*
X425897Y408050D01*
X426242Y407998D01*
X426587Y407792D01*
G01X422950Y404950D02*
Y408050D01*
X423410Y407430D01*
G01Y404950D02*
X422490D01*
G01X419927D02*
X419850Y405622D01*
X419735Y406190D01*
X419582Y406707D01*
X419390Y407275D01*
X419083Y408050D01*
X420617D01*
G01X429917Y409950D02*
Y413050D01*
X428958D01*
X428652Y412895D01*
X428460Y412688D01*
X428383Y412275D01*
X428460Y411862D01*
X428690Y411603D01*
X428958Y411448D01*
X429917D01*
G01X428958D02*
X428383Y409950D01*
G01X426893Y410570D02*
X426663Y410208D01*
X426357Y410002D01*
X426012Y409950D01*
X425705Y410002D01*
X425398Y410260D01*
X425207Y410570D01*
X425168Y410880D01*
X425245Y411242D01*
X425513Y411500D01*
X425782Y411603D01*
X426127D01*
G01X425782D02*
X425552Y411758D01*
X425360Y412017D01*
X425283Y412327D01*
X425360Y412637D01*
X425552Y412895D01*
X425897Y413050D01*
X426242Y412998D01*
X426587Y412792D01*
G01X422950Y409950D02*
Y413050D01*
X423410Y412430D01*
G01Y409950D02*
X422490D01*
G01X419850D02*
X419582Y410002D01*
X419275Y410157D01*
X419083Y410415D01*
X419007Y410777D01*
X419083Y411138D01*
X419313Y411448D01*
X419658Y411603D01*
X420042D01*
X420272Y411707D01*
X420463Y411965D01*
X420540Y412327D01*
X420425Y412688D01*
X420157Y412947D01*
X419850Y413050D01*
X419543Y412947D01*
X419275Y412688D01*
X419160Y412327D01*
X419237Y411965D01*
X419428Y411707D01*
X419658Y411603D01*
X420042D01*
X420387Y411448D01*
X420617Y411138D01*
X420693Y410777D01*
X420617Y410415D01*
X420425Y410157D01*
X420118Y410002D01*
X419850Y409950D01*
G01X433292Y90193D02*
X433447Y89963D01*
X433550Y89695D01*
Y89388D01*
X433395Y89043D01*
X433137Y88775D01*
X432827Y88583D01*
X432310Y88430D01*
X431845Y88392D01*
X431380Y88468D01*
X431070Y88583D01*
X430760Y88813D01*
X430553Y89082D01*
X430450Y89350D01*
Y89618D01*
X430553Y89887D01*
X430708Y90117D01*
X430915Y90308D01*
G01X433033Y91722D02*
X433343Y91952D01*
X433498Y92220D01*
X433550Y92527D01*
X433447Y92910D01*
X433188Y93178D01*
X432878Y93255D01*
X432568Y93217D01*
X432310Y93063D01*
X431793Y92297D01*
X431432Y91952D01*
X430915Y91722D01*
X430450Y91645D01*
Y93255D01*
G01Y96010D02*
X433550D01*
X431328Y94592D01*
Y96508D01*
G01X430450Y98650D02*
X430502Y98918D01*
X430657Y99225D01*
X430915Y99417D01*
X431277Y99493D01*
X431638Y99417D01*
X431948Y99187D01*
X432103Y98842D01*
Y98458D01*
X432207Y98228D01*
X432465Y98037D01*
X432827Y97960D01*
X433188Y98075D01*
X433447Y98343D01*
X433550Y98650D01*
X433447Y98957D01*
X433188Y99225D01*
X432827Y99340D01*
X432465Y99263D01*
X432207Y99072D01*
X432103Y98842D01*
Y98458D01*
X431948Y98113D01*
X431638Y97883D01*
X431277Y97807D01*
X430915Y97883D01*
X430657Y98075D01*
X430502Y98382D01*
X430450Y98650D01*
G01X440466Y104583D02*
X443566D01*
Y105542D01*
X443411Y105848D01*
X443204Y106040D01*
X442791Y106117D01*
X442378Y106040D01*
X442119Y105810D01*
X441964Y105542D01*
Y104583D01*
G01Y105542D02*
X440466Y106117D01*
G01X441086Y107607D02*
X440724Y107837D01*
X440518Y108143D01*
X440466Y108488D01*
X440518Y108795D01*
X440776Y109102D01*
X441086Y109293D01*
X441396Y109332D01*
X441758Y109255D01*
X442016Y108987D01*
X442119Y108718D01*
Y108373D01*
G01Y108718D02*
X442274Y108948D01*
X442533Y109140D01*
X442843Y109217D01*
X443153Y109140D01*
X443411Y108948D01*
X443566Y108603D01*
X443514Y108258D01*
X443308Y107913D01*
G01X440931Y110707D02*
X440673Y110937D01*
X440518Y111205D01*
X440466Y111550D01*
X440569Y111895D01*
X440776Y112163D01*
X441138Y112355D01*
X441551Y112393D01*
X441964Y112317D01*
X442223Y112125D01*
X442429Y111857D01*
X442481Y111588D01*
X442429Y111320D01*
X442223Y110975D01*
X443566Y111090D01*
Y112125D01*
G01X440466Y114650D02*
X440518Y114918D01*
X440673Y115225D01*
X440931Y115417D01*
X441293Y115493D01*
X441654Y115417D01*
X441964Y115187D01*
X442119Y114842D01*
Y114458D01*
X442223Y114228D01*
X442481Y114037D01*
X442843Y113960D01*
X443204Y114075D01*
X443463Y114343D01*
X443566Y114650D01*
X443463Y114957D01*
X443204Y115225D01*
X442843Y115340D01*
X442481Y115263D01*
X442223Y115072D01*
X442119Y114842D01*
Y114458D01*
X441964Y114113D01*
X441654Y113883D01*
X441293Y113807D01*
X440931Y113883D01*
X440673Y114075D01*
X440518Y114382D01*
X440466Y114650D01*
G01X435966Y104583D02*
X439066D01*
Y105542D01*
X438911Y105848D01*
X438704Y106040D01*
X438291Y106117D01*
X437878Y106040D01*
X437619Y105810D01*
X437464Y105542D01*
Y104583D01*
G01Y105542D02*
X435966Y106117D01*
G01X436586Y107607D02*
X436224Y107837D01*
X436018Y108143D01*
X435966Y108488D01*
X436018Y108795D01*
X436276Y109102D01*
X436586Y109293D01*
X436896Y109332D01*
X437258Y109255D01*
X437516Y108987D01*
X437619Y108718D01*
Y108373D01*
G01Y108718D02*
X437774Y108948D01*
X438033Y109140D01*
X438343Y109217D01*
X438653Y109140D01*
X438911Y108948D01*
X439066Y108603D01*
X439014Y108258D01*
X438808Y107913D01*
G01X436431Y110707D02*
X436173Y110937D01*
X436018Y111205D01*
X435966Y111550D01*
X436069Y111895D01*
X436276Y112163D01*
X436638Y112355D01*
X437051Y112393D01*
X437464Y112317D01*
X437723Y112125D01*
X437929Y111857D01*
X437981Y111588D01*
X437929Y111320D01*
X437723Y110975D01*
X439066Y111090D01*
Y112125D01*
G01X436431Y113807D02*
X436173Y114037D01*
X436018Y114305D01*
X435966Y114650D01*
X436069Y114995D01*
X436276Y115263D01*
X436638Y115455D01*
X437051Y115493D01*
X437464Y115417D01*
X437723Y115225D01*
X437929Y114957D01*
X437981Y114688D01*
X437929Y114420D01*
X437723Y114075D01*
X439066Y114190D01*
Y115225D01*
G01X441085Y132417D02*
X441210Y132257D01*
X441293Y132070D01*
Y131857D01*
X441168Y131617D01*
X440960Y131430D01*
X440710Y131297D01*
X440293Y131190D01*
X439918Y131163D01*
X439543Y131217D01*
X439293Y131297D01*
X439043Y131457D01*
X438876Y131643D01*
X438793Y131830D01*
Y132017D01*
X438876Y132203D01*
X439001Y132363D01*
X439168Y132497D01*
G01X438793Y134030D02*
X441293D01*
X440793Y133710D01*
G01X438793D02*
Y134350D01*
G01X441293Y136230D02*
X441210Y136017D01*
X441001Y135857D01*
X440751Y135750D01*
X440418Y135670D01*
X440043Y135643D01*
X439668Y135670D01*
X439335Y135750D01*
X439085Y135857D01*
X438876Y136017D01*
X438793Y136230D01*
X438876Y136443D01*
X439085Y136603D01*
X439335Y136710D01*
X439668Y136790D01*
X440043Y136817D01*
X440418Y136790D01*
X440751Y136710D01*
X441001Y136603D01*
X441210Y136443D01*
X441293Y136230D01*
G01X438793Y138430D02*
X438835Y138617D01*
X438960Y138830D01*
X439168Y138963D01*
X439460Y139017D01*
X439751Y138963D01*
X440001Y138803D01*
X440126Y138563D01*
Y138297D01*
X440210Y138137D01*
X440418Y138003D01*
X440710Y137950D01*
X441001Y138030D01*
X441210Y138217D01*
X441293Y138430D01*
X441210Y138643D01*
X441001Y138830D01*
X440710Y138910D01*
X440418Y138857D01*
X440210Y138723D01*
X440126Y138563D01*
Y138297D01*
X440001Y138057D01*
X439751Y137897D01*
X439460Y137843D01*
X439168Y137897D01*
X438960Y138030D01*
X438835Y138243D01*
X438793Y138430D01*
G01X445024Y140291D02*
X445149Y140131D01*
X445232Y139944D01*
Y139731D01*
X445107Y139491D01*
X444899Y139304D01*
X444649Y139171D01*
X444232Y139064D01*
X443857Y139037D01*
X443482Y139091D01*
X443232Y139171D01*
X442982Y139331D01*
X442815Y139517D01*
X442732Y139704D01*
Y139891D01*
X442815Y140077D01*
X442940Y140237D01*
X443107Y140371D01*
G01X442732Y141904D02*
X445232D01*
X444732Y141584D01*
G01X442732D02*
Y142224D01*
G01X443232Y143517D02*
X442940Y143677D01*
X442774Y143891D01*
X442732Y144131D01*
X442774Y144344D01*
X442982Y144557D01*
X443232Y144691D01*
X443482Y144717D01*
X443774Y144664D01*
X443982Y144477D01*
X444065Y144291D01*
Y144051D01*
G01Y144291D02*
X444190Y144451D01*
X444399Y144584D01*
X444649Y144637D01*
X444899Y144584D01*
X445107Y144451D01*
X445232Y144211D01*
X445190Y143971D01*
X445024Y143731D01*
G01X443107Y145717D02*
X442899Y145877D01*
X442774Y146064D01*
X442732Y146304D01*
X442815Y146544D01*
X442982Y146731D01*
X443274Y146864D01*
X443607Y146891D01*
X443940Y146837D01*
X444149Y146704D01*
X444315Y146517D01*
X444357Y146331D01*
X444315Y146144D01*
X444149Y145904D01*
X445232Y145984D01*
Y146704D01*
G01X437292Y141787D02*
X437417Y141627D01*
X437500Y141440D01*
Y141227D01*
X437375Y140987D01*
X437167Y140800D01*
X436917Y140667D01*
X436500Y140560D01*
X436125Y140533D01*
X435750Y140587D01*
X435500Y140667D01*
X435250Y140827D01*
X435083Y141013D01*
X435000Y141200D01*
Y141387D01*
X435083Y141573D01*
X435208Y141733D01*
X435375Y141867D01*
G01X437083Y142893D02*
X437333Y143053D01*
X437458Y143240D01*
X437500Y143453D01*
X437417Y143720D01*
X437208Y143907D01*
X436958Y143960D01*
X436708Y143933D01*
X436500Y143827D01*
X436083Y143293D01*
X435792Y143053D01*
X435375Y142893D01*
X435000Y142840D01*
Y143960D01*
G01X437083Y145093D02*
X437333Y145253D01*
X437458Y145440D01*
X437500Y145653D01*
X437417Y145920D01*
X437208Y146107D01*
X436958Y146160D01*
X436708Y146133D01*
X436500Y146027D01*
X436083Y145493D01*
X435792Y145253D01*
X435375Y145093D01*
X435000Y145040D01*
Y146160D01*
G01X437500Y147800D02*
X437417Y147587D01*
X437208Y147427D01*
X436958Y147320D01*
X436625Y147240D01*
X436250Y147213D01*
X435875Y147240D01*
X435542Y147320D01*
X435292Y147427D01*
X435083Y147587D01*
X435000Y147800D01*
X435083Y148013D01*
X435292Y148173D01*
X435542Y148280D01*
X435875Y148360D01*
X436250Y148387D01*
X436625Y148360D01*
X436958Y148280D01*
X437208Y148173D01*
X437417Y148013D01*
X437500Y147800D01*
G01X441585Y154539D02*
X441710Y154379D01*
X441793Y154192D01*
Y153979D01*
X441668Y153739D01*
X441460Y153552D01*
X441210Y153419D01*
X440793Y153312D01*
X440418Y153285D01*
X440043Y153339D01*
X439793Y153419D01*
X439543Y153579D01*
X439376Y153765D01*
X439293Y153952D01*
Y154139D01*
X439376Y154325D01*
X439501Y154485D01*
X439668Y154619D01*
G01X439293Y156152D02*
X441793D01*
X441293Y155832D01*
G01X439293D02*
Y156472D01*
G01Y158299D02*
X439835Y158352D01*
X440293Y158432D01*
X440710Y158539D01*
X441168Y158672D01*
X441793Y158885D01*
Y157819D01*
G01X439293Y160552D02*
X441793D01*
X441293Y160232D01*
G01X439293D02*
Y160872D01*
G01X448962Y165400D02*
X449122Y165525D01*
X449309Y165608D01*
X449522D01*
X449762Y165483D01*
X449949Y165275D01*
X450082Y165025D01*
X450189Y164608D01*
X450216Y164233D01*
X450162Y163858D01*
X450082Y163608D01*
X449922Y163358D01*
X449736Y163191D01*
X449549Y163108D01*
X449362D01*
X449176Y163191D01*
X449016Y163316D01*
X448882Y163483D01*
G01X447349Y163108D02*
Y165608D01*
X447669Y165108D01*
G01Y163108D02*
X447029D01*
G01X444829D02*
Y165608D01*
X445816Y163816D01*
X444482D01*
G01X443002Y163108D02*
X442949Y163650D01*
X442869Y164108D01*
X442762Y164525D01*
X442629Y164983D01*
X442416Y165608D01*
X443482D01*
G01X445524Y154540D02*
X445649Y154380D01*
X445732Y154193D01*
Y153980D01*
X445607Y153740D01*
X445399Y153553D01*
X445149Y153420D01*
X444732Y153313D01*
X444357Y153286D01*
X443982Y153340D01*
X443732Y153420D01*
X443482Y153580D01*
X443315Y153766D01*
X443232Y153953D01*
Y154140D01*
X443315Y154326D01*
X443440Y154486D01*
X443607Y154620D01*
G01X443232Y156153D02*
X445732D01*
X445232Y155833D01*
G01X443232D02*
Y156473D01*
G01X444274Y157846D02*
X444565Y158033D01*
X444732Y158193D01*
X444815Y158406D01*
X444732Y158593D01*
X444565Y158726D01*
X444315Y158833D01*
X444024Y158860D01*
X443774Y158833D01*
X443524Y158726D01*
X443315Y158566D01*
X443232Y158380D01*
X443315Y158166D01*
X443565Y157980D01*
X443940Y157873D01*
X444357Y157846D01*
X444899Y157900D01*
X445190Y157980D01*
X445482Y158113D01*
X445690Y158300D01*
X445732Y158486D01*
X445649Y158673D01*
X445440Y158806D01*
G01X443232Y160553D02*
X445732D01*
X445232Y160233D01*
G01X443232D02*
Y160873D01*
G01X441085Y163913D02*
X441210Y163753D01*
X441293Y163566D01*
Y163353D01*
X441168Y163113D01*
X440960Y162926D01*
X440710Y162793D01*
X440293Y162686D01*
X439918Y162659D01*
X439543Y162713D01*
X439293Y162793D01*
X439043Y162953D01*
X438876Y163139D01*
X438793Y163326D01*
Y163513D01*
X438876Y163699D01*
X439001Y163859D01*
X439168Y163993D01*
G01X440876Y165019D02*
X441126Y165179D01*
X441251Y165366D01*
X441293Y165579D01*
X441210Y165846D01*
X441001Y166033D01*
X440751Y166086D01*
X440501Y166059D01*
X440293Y165953D01*
X439876Y165419D01*
X439585Y165179D01*
X439168Y165019D01*
X438793Y164966D01*
Y166086D01*
G01X441293Y167726D02*
X441210Y167513D01*
X441001Y167353D01*
X440751Y167246D01*
X440418Y167166D01*
X440043Y167139D01*
X439668Y167166D01*
X439335Y167246D01*
X439085Y167353D01*
X438876Y167513D01*
X438793Y167726D01*
X438876Y167939D01*
X439085Y168099D01*
X439335Y168206D01*
X439668Y168286D01*
X440043Y168313D01*
X440418Y168286D01*
X440751Y168206D01*
X441001Y168099D01*
X441210Y167939D01*
X441293Y167726D01*
G01X438793Y169926D02*
X441293D01*
X440793Y169606D01*
G01X438793D02*
Y170246D01*
G01X436792Y162787D02*
X436917Y162627D01*
X437000Y162440D01*
Y162227D01*
X436875Y161987D01*
X436667Y161800D01*
X436417Y161667D01*
X436000Y161560D01*
X435625Y161533D01*
X435250Y161587D01*
X435000Y161667D01*
X434750Y161827D01*
X434583Y162013D01*
X434500Y162200D01*
Y162387D01*
X434583Y162573D01*
X434708Y162733D01*
X434875Y162867D01*
G01X434500Y164400D02*
X437000D01*
X436500Y164080D01*
G01X434500D02*
Y164720D01*
G01X436583Y166093D02*
X436833Y166253D01*
X436958Y166440D01*
X437000Y166653D01*
X436917Y166920D01*
X436708Y167107D01*
X436458Y167160D01*
X436208Y167133D01*
X436000Y167027D01*
X435583Y166493D01*
X435292Y166253D01*
X434875Y166093D01*
X434500Y166040D01*
Y167160D01*
G01X434792Y168347D02*
X434583Y168533D01*
X434500Y168747D01*
X434583Y168960D01*
X434833Y169147D01*
X435208Y169280D01*
X435583Y169333D01*
X436042D01*
X436417Y169280D01*
X436750Y169147D01*
X436917Y168987D01*
X437000Y168800D01*
X436917Y168587D01*
X436750Y168427D01*
X436500Y168320D01*
X436167Y168267D01*
X435875Y168320D01*
X435583Y168453D01*
X435417Y168613D01*
X435375Y168800D01*
X435458Y169013D01*
X435667Y169173D01*
X436042Y169333D01*
G01X437292Y152287D02*
X437417Y152127D01*
X437500Y151940D01*
Y151727D01*
X437375Y151487D01*
X437167Y151300D01*
X436917Y151167D01*
X436500Y151060D01*
X436125Y151033D01*
X435750Y151087D01*
X435500Y151167D01*
X435250Y151327D01*
X435083Y151513D01*
X435000Y151700D01*
Y151887D01*
X435083Y152073D01*
X435208Y152233D01*
X435375Y152367D01*
G01X437083Y153393D02*
X437333Y153553D01*
X437458Y153740D01*
X437500Y153953D01*
X437417Y154220D01*
X437208Y154407D01*
X436958Y154460D01*
X436708Y154433D01*
X436500Y154327D01*
X436083Y153793D01*
X435792Y153553D01*
X435375Y153393D01*
X435000Y153340D01*
Y154460D01*
G01Y156100D02*
X437500D01*
X437000Y155780D01*
G01X435000D02*
Y156420D01*
G01Y158620D02*
X437500D01*
X435708Y157633D01*
Y158967D01*
G01X437113Y174842D02*
X437273Y174967D01*
X437460Y175050D01*
X437673D01*
X437913Y174925D01*
X438100Y174717D01*
X438233Y174467D01*
X438340Y174050D01*
X438367Y173675D01*
X438313Y173300D01*
X438233Y173050D01*
X438073Y172800D01*
X437887Y172633D01*
X437700Y172550D01*
X437513D01*
X437327Y172633D01*
X437167Y172758D01*
X437033Y172925D01*
G01X436007Y174633D02*
X435847Y174883D01*
X435660Y175008D01*
X435447Y175050D01*
X435180Y174967D01*
X434993Y174758D01*
X434940Y174508D01*
X434967Y174258D01*
X435073Y174050D01*
X435607Y173633D01*
X435847Y173342D01*
X436007Y172925D01*
X436060Y172550D01*
X434940D01*
G01X433300D02*
Y175050D01*
X433620Y174550D01*
G01Y172550D02*
X432980D01*
G01X431607Y174633D02*
X431447Y174883D01*
X431260Y175008D01*
X431047Y175050D01*
X430780Y174967D01*
X430593Y174758D01*
X430540Y174508D01*
X430567Y174258D01*
X430673Y174050D01*
X431207Y173633D01*
X431447Y173342D01*
X431607Y172925D01*
X431660Y172550D01*
X430540D01*
G01X447124Y176242D02*
X447284Y176367D01*
X447471Y176450D01*
X447684D01*
X447924Y176325D01*
X448111Y176117D01*
X448244Y175867D01*
X448351Y175450D01*
X448378Y175075D01*
X448324Y174700D01*
X448244Y174450D01*
X448084Y174200D01*
X447898Y174033D01*
X447711Y173950D01*
X447524D01*
X447338Y174033D01*
X447178Y174158D01*
X447044Y174325D01*
G01X445511Y173950D02*
Y176450D01*
X445831Y175950D01*
G01Y173950D02*
X445191D01*
G01X443818Y176033D02*
X443658Y176283D01*
X443471Y176408D01*
X443258Y176450D01*
X442991Y176367D01*
X442804Y176158D01*
X442751Y175908D01*
X442778Y175658D01*
X442884Y175450D01*
X443418Y175033D01*
X443658Y174742D01*
X443818Y174325D01*
X443871Y173950D01*
X442751D01*
G01X441111D02*
X440924Y173992D01*
X440711Y174117D01*
X440578Y174325D01*
X440524Y174617D01*
X440578Y174908D01*
X440738Y175158D01*
X440978Y175283D01*
X441244D01*
X441404Y175367D01*
X441538Y175575D01*
X441591Y175867D01*
X441511Y176158D01*
X441324Y176367D01*
X441111Y176450D01*
X440898Y176367D01*
X440711Y176158D01*
X440631Y175867D01*
X440684Y175575D01*
X440818Y175367D01*
X440978Y175283D01*
X441244D01*
X441484Y175158D01*
X441644Y174908D01*
X441698Y174617D01*
X441644Y174325D01*
X441511Y174117D01*
X441298Y173992D01*
X441111Y173950D01*
G01X448962Y169337D02*
X449122Y169462D01*
X449309Y169545D01*
X449522D01*
X449762Y169420D01*
X449949Y169212D01*
X450082Y168962D01*
X450189Y168545D01*
X450216Y168170D01*
X450162Y167795D01*
X450082Y167545D01*
X449922Y167295D01*
X449736Y167128D01*
X449549Y167045D01*
X449362D01*
X449176Y167128D01*
X449016Y167253D01*
X448882Y167420D01*
G01X447349Y167045D02*
Y169545D01*
X447669Y169045D01*
G01Y167045D02*
X447029D01*
G01X445736Y167545D02*
X445576Y167253D01*
X445362Y167087D01*
X445122Y167045D01*
X444909Y167087D01*
X444696Y167295D01*
X444562Y167545D01*
X444536Y167795D01*
X444589Y168087D01*
X444776Y168295D01*
X444962Y168378D01*
X445202D01*
G01X444962D02*
X444802Y168503D01*
X444669Y168712D01*
X444616Y168962D01*
X444669Y169212D01*
X444802Y169420D01*
X445042Y169545D01*
X445282Y169503D01*
X445522Y169337D01*
G01X442949Y167045D02*
X442762Y167087D01*
X442549Y167212D01*
X442416Y167420D01*
X442362Y167712D01*
X442416Y168003D01*
X442576Y168253D01*
X442816Y168378D01*
X443082D01*
X443242Y168462D01*
X443376Y168670D01*
X443429Y168962D01*
X443349Y169253D01*
X443162Y169462D01*
X442949Y169545D01*
X442736Y169462D01*
X442549Y169253D01*
X442469Y168962D01*
X442522Y168670D01*
X442656Y168462D01*
X442816Y168378D01*
X443082D01*
X443322Y168253D01*
X443482Y168003D01*
X443536Y167712D01*
X443482Y167420D01*
X443349Y167212D01*
X443136Y167087D01*
X442949Y167045D01*
G01X440713Y181542D02*
X440873Y181667D01*
X441060Y181750D01*
X441273D01*
X441513Y181625D01*
X441700Y181417D01*
X441833Y181167D01*
X441940Y180750D01*
X441967Y180375D01*
X441913Y180000D01*
X441833Y179750D01*
X441673Y179500D01*
X441487Y179333D01*
X441300Y179250D01*
X441113D01*
X440927Y179333D01*
X440767Y179458D01*
X440633Y179625D01*
G01X439607Y181333D02*
X439447Y181583D01*
X439260Y181708D01*
X439047Y181750D01*
X438780Y181667D01*
X438593Y181458D01*
X438540Y181208D01*
X438567Y180958D01*
X438673Y180750D01*
X439207Y180333D01*
X439447Y180042D01*
X439607Y179625D01*
X439660Y179250D01*
X438540D01*
G01X436900Y181750D02*
X437113Y181667D01*
X437273Y181458D01*
X437380Y181208D01*
X437460Y180875D01*
X437487Y180500D01*
X437460Y180125D01*
X437380Y179792D01*
X437273Y179542D01*
X437113Y179333D01*
X436900Y179250D01*
X436687Y179333D01*
X436527Y179542D01*
X436420Y179792D01*
X436340Y180125D01*
X436313Y180500D01*
X436340Y180875D01*
X436420Y181208D01*
X436527Y181458D01*
X436687Y181667D01*
X436900Y181750D01*
G01X435207Y180292D02*
X435020Y180583D01*
X434860Y180750D01*
X434647Y180833D01*
X434460Y180750D01*
X434327Y180583D01*
X434220Y180333D01*
X434193Y180042D01*
X434220Y179792D01*
X434327Y179542D01*
X434487Y179333D01*
X434673Y179250D01*
X434887Y179333D01*
X435073Y179583D01*
X435180Y179958D01*
X435207Y180375D01*
X435153Y180917D01*
X435073Y181208D01*
X434940Y181500D01*
X434753Y181708D01*
X434567Y181750D01*
X434380Y181667D01*
X434247Y181458D01*
G01X443246Y178541D02*
X445746D01*
Y179207D01*
X445621Y179421D01*
X445454Y179554D01*
X445121Y179607D01*
X444788Y179554D01*
X444579Y179394D01*
X444454Y179207D01*
Y178541D01*
G01Y179207D02*
X443246Y179607D01*
G01Y181594D02*
X445746D01*
X443954Y180607D01*
Y181941D01*
G01X443746Y182887D02*
X443454Y183047D01*
X443288Y183261D01*
X443246Y183501D01*
X443288Y183714D01*
X443496Y183927D01*
X443746Y184061D01*
X443996Y184087D01*
X444288Y184034D01*
X444496Y183847D01*
X444579Y183661D01*
Y183421D01*
G01Y183661D02*
X444704Y183821D01*
X444913Y183954D01*
X445163Y184007D01*
X445413Y183954D01*
X445621Y183821D01*
X445746Y183581D01*
X445704Y183341D01*
X445538Y183101D01*
G01X444288Y185167D02*
X444579Y185354D01*
X444746Y185514D01*
X444829Y185727D01*
X444746Y185914D01*
X444579Y186047D01*
X444329Y186154D01*
X444038Y186181D01*
X443788Y186154D01*
X443538Y186047D01*
X443329Y185887D01*
X443246Y185701D01*
X443329Y185487D01*
X443579Y185301D01*
X443954Y185194D01*
X444371Y185167D01*
X444913Y185221D01*
X445204Y185301D01*
X445496Y185434D01*
X445704Y185621D01*
X445746Y185807D01*
X445663Y185994D01*
X445454Y186127D01*
G01X445024Y192959D02*
X445184Y193084D01*
X445371Y193167D01*
X445584D01*
X445824Y193042D01*
X446011Y192834D01*
X446144Y192584D01*
X446251Y192167D01*
X446278Y191792D01*
X446224Y191417D01*
X446144Y191167D01*
X445984Y190917D01*
X445798Y190750D01*
X445611Y190667D01*
X445424D01*
X445238Y190750D01*
X445078Y190875D01*
X444944Y191042D01*
G01X443411Y190667D02*
Y193167D01*
X443731Y192667D01*
G01Y190667D02*
X443091D01*
G01X441798Y191167D02*
X441638Y190875D01*
X441424Y190709D01*
X441184Y190667D01*
X440971Y190709D01*
X440758Y190917D01*
X440624Y191167D01*
X440598Y191417D01*
X440651Y191709D01*
X440838Y191917D01*
X441024Y192000D01*
X441264D01*
G01X441024D02*
X440864Y192125D01*
X440731Y192334D01*
X440678Y192584D01*
X440731Y192834D01*
X440864Y193042D01*
X441104Y193167D01*
X441344Y193125D01*
X441584Y192959D01*
G01X439518Y192750D02*
X439358Y193000D01*
X439171Y193125D01*
X438958Y193167D01*
X438691Y193084D01*
X438504Y192875D01*
X438451Y192625D01*
X438478Y192375D01*
X438584Y192167D01*
X439118Y191750D01*
X439358Y191459D01*
X439518Y191042D01*
X439571Y190667D01*
X438451D01*
G01X441635Y214001D02*
X441790Y213771D01*
X441893Y213503D01*
Y213196D01*
X441738Y212851D01*
X441480Y212583D01*
X441170Y212391D01*
X440653Y212238D01*
X440188Y212200D01*
X439723Y212276D01*
X439413Y212391D01*
X439103Y212621D01*
X438896Y212890D01*
X438793Y213158D01*
Y213426D01*
X438896Y213695D01*
X439051Y213925D01*
X439258Y214116D01*
G01X441376Y215530D02*
X441686Y215760D01*
X441841Y216028D01*
X441893Y216335D01*
X441790Y216718D01*
X441531Y216986D01*
X441221Y217063D01*
X440911Y217025D01*
X440653Y216871D01*
X440136Y216105D01*
X439775Y215760D01*
X439258Y215530D01*
X438793Y215453D01*
Y217063D01*
G01X441376Y218630D02*
X441686Y218860D01*
X441841Y219128D01*
X441893Y219435D01*
X441790Y219818D01*
X441531Y220086D01*
X441221Y220163D01*
X440911Y220125D01*
X440653Y219971D01*
X440136Y219205D01*
X439775Y218860D01*
X439258Y218630D01*
X438793Y218553D01*
Y220163D01*
G01X439413Y221615D02*
X439051Y221845D01*
X438845Y222151D01*
X438793Y222496D01*
X438845Y222803D01*
X439103Y223110D01*
X439413Y223301D01*
X439723Y223340D01*
X440085Y223263D01*
X440343Y222995D01*
X440446Y222726D01*
Y222381D01*
G01Y222726D02*
X440601Y222956D01*
X440860Y223148D01*
X441170Y223225D01*
X441480Y223148D01*
X441738Y222956D01*
X441893Y222611D01*
X441841Y222266D01*
X441635Y221921D01*
G01X453992Y209257D02*
X454222Y209412D01*
X454490Y209515D01*
X454797D01*
X455142Y209360D01*
X455410Y209102D01*
X455602Y208792D01*
X455755Y208275D01*
X455793Y207810D01*
X455717Y207345D01*
X455602Y207035D01*
X455372Y206725D01*
X455103Y206518D01*
X454835Y206415D01*
X454567D01*
X454298Y206518D01*
X454068Y206673D01*
X453877Y206880D01*
G01X451735Y206415D02*
Y209515D01*
X452195Y208895D01*
G01Y206415D02*
X451275D01*
G01X449478Y207035D02*
X449248Y206673D01*
X448942Y206467D01*
X448597Y206415D01*
X448290Y206467D01*
X447983Y206725D01*
X447792Y207035D01*
X447753Y207345D01*
X447830Y207707D01*
X448098Y207965D01*
X448367Y208068D01*
X448712D01*
G01X448367D02*
X448137Y208223D01*
X447945Y208482D01*
X447868Y208792D01*
X447945Y209102D01*
X448137Y209360D01*
X448482Y209515D01*
X448827Y209463D01*
X449172Y209257D01*
G01X445075Y206415D02*
Y209515D01*
X446493Y207293D01*
X444577D01*
G01X452307Y223342D02*
X452537Y223497D01*
X452805Y223600D01*
X453112D01*
X453457Y223445D01*
X453725Y223187D01*
X453917Y222877D01*
X454070Y222360D01*
X454108Y221895D01*
X454032Y221430D01*
X453917Y221120D01*
X453687Y220810D01*
X453418Y220603D01*
X453150Y220500D01*
X452882D01*
X452613Y220603D01*
X452383Y220758D01*
X452192Y220965D01*
G01X450050Y220500D02*
Y223600D01*
X450510Y222980D01*
G01Y220500D02*
X449590D01*
G01X447678Y221792D02*
X447410Y222153D01*
X447180Y222360D01*
X446873Y222463D01*
X446605Y222360D01*
X446413Y222153D01*
X446260Y221843D01*
X446222Y221482D01*
X446260Y221172D01*
X446413Y220862D01*
X446643Y220603D01*
X446912Y220500D01*
X447218Y220603D01*
X447487Y220913D01*
X447640Y221378D01*
X447678Y221895D01*
X447602Y222567D01*
X447487Y222928D01*
X447295Y223290D01*
X447027Y223548D01*
X446758Y223600D01*
X446490Y223497D01*
X446298Y223238D01*
G01X444693Y221120D02*
X444463Y220758D01*
X444157Y220552D01*
X443812Y220500D01*
X443505Y220552D01*
X443198Y220810D01*
X443007Y221120D01*
X442968Y221430D01*
X443045Y221792D01*
X443313Y222050D01*
X443582Y222153D01*
X443927D01*
G01X443582D02*
X443352Y222308D01*
X443160Y222567D01*
X443083Y222877D01*
X443160Y223187D01*
X443352Y223445D01*
X443697Y223600D01*
X444042Y223548D01*
X444387Y223342D01*
G01X433450Y238583D02*
X436550D01*
Y239542D01*
X436395Y239848D01*
X436188Y240040D01*
X435775Y240117D01*
X435362Y240040D01*
X435103Y239810D01*
X434948Y239542D01*
Y238583D01*
G01Y239542D02*
X433450Y240117D01*
G01X436033Y241722D02*
X436343Y241952D01*
X436498Y242220D01*
X436550Y242527D01*
X436447Y242910D01*
X436188Y243178D01*
X435878Y243255D01*
X435568Y243217D01*
X435310Y243063D01*
X434793Y242297D01*
X434432Y241952D01*
X433915Y241722D01*
X433450Y241645D01*
Y243255D01*
G01X436550Y245550D02*
X436447Y245243D01*
X436188Y245013D01*
X435878Y244860D01*
X435465Y244745D01*
X435000Y244707D01*
X434535Y244745D01*
X434122Y244860D01*
X433812Y245013D01*
X433553Y245243D01*
X433450Y245550D01*
X433553Y245857D01*
X433812Y246087D01*
X434122Y246240D01*
X434535Y246355D01*
X435000Y246393D01*
X435465Y246355D01*
X435878Y246240D01*
X436188Y246087D01*
X436447Y245857D01*
X436550Y245550D01*
G01X433450Y248573D02*
X434122Y248650D01*
X434690Y248765D01*
X435207Y248918D01*
X435775Y249110D01*
X436550Y249417D01*
Y247883D01*
G01X442450Y238583D02*
X445550D01*
Y239542D01*
X445395Y239848D01*
X445188Y240040D01*
X444775Y240117D01*
X444362Y240040D01*
X444103Y239810D01*
X443948Y239542D01*
Y238583D01*
G01Y239542D02*
X442450Y240117D01*
G01X445033Y241722D02*
X445343Y241952D01*
X445498Y242220D01*
X445550Y242527D01*
X445447Y242910D01*
X445188Y243178D01*
X444878Y243255D01*
X444568Y243217D01*
X444310Y243063D01*
X443793Y242297D01*
X443432Y241952D01*
X442915Y241722D01*
X442450Y241645D01*
Y243255D01*
G01X445033Y244822D02*
X445343Y245052D01*
X445498Y245320D01*
X445550Y245627D01*
X445447Y246010D01*
X445188Y246278D01*
X444878Y246355D01*
X444568Y246317D01*
X444310Y246163D01*
X443793Y245397D01*
X443432Y245052D01*
X442915Y244822D01*
X442450Y244745D01*
Y246355D01*
G01X445550Y248650D02*
X445447Y248343D01*
X445188Y248113D01*
X444878Y247960D01*
X444465Y247845D01*
X444000Y247807D01*
X443535Y247845D01*
X443122Y247960D01*
X442812Y248113D01*
X442553Y248343D01*
X442450Y248650D01*
X442553Y248957D01*
X442812Y249187D01*
X443122Y249340D01*
X443535Y249455D01*
X444000Y249493D01*
X444465Y249455D01*
X444878Y249340D01*
X445188Y249187D01*
X445447Y248957D01*
X445550Y248650D01*
G01X437950Y238583D02*
X441050D01*
Y239542D01*
X440895Y239848D01*
X440688Y240040D01*
X440275Y240117D01*
X439862Y240040D01*
X439603Y239810D01*
X439448Y239542D01*
Y238583D01*
G01Y239542D02*
X437950Y240117D01*
G01X440533Y241722D02*
X440843Y241952D01*
X440998Y242220D01*
X441050Y242527D01*
X440947Y242910D01*
X440688Y243178D01*
X440378Y243255D01*
X440068Y243217D01*
X439810Y243063D01*
X439293Y242297D01*
X438932Y241952D01*
X438415Y241722D01*
X437950Y241645D01*
Y243255D01*
G01Y245550D02*
X441050D01*
X440430Y245090D01*
G01X437950D02*
Y246010D01*
G01X438312Y247998D02*
X438053Y248267D01*
X437950Y248573D01*
X438053Y248880D01*
X438363Y249148D01*
X438828Y249340D01*
X439293Y249417D01*
X439862D01*
X440327Y249340D01*
X440740Y249148D01*
X440947Y248918D01*
X441050Y248650D01*
X440947Y248343D01*
X440740Y248113D01*
X440430Y247960D01*
X440017Y247883D01*
X439655Y247960D01*
X439293Y248152D01*
X439087Y248382D01*
X439035Y248650D01*
X439138Y248957D01*
X439397Y249187D01*
X439862Y249417D01*
G01X446950Y238583D02*
X450050D01*
Y239542D01*
X449895Y239848D01*
X449688Y240040D01*
X449275Y240117D01*
X448862Y240040D01*
X448603Y239810D01*
X448448Y239542D01*
Y238583D01*
G01Y239542D02*
X446950Y240117D01*
G01X449533Y241722D02*
X449843Y241952D01*
X449998Y242220D01*
X450050Y242527D01*
X449947Y242910D01*
X449688Y243178D01*
X449378Y243255D01*
X449068Y243217D01*
X448810Y243063D01*
X448293Y242297D01*
X447932Y241952D01*
X447415Y241722D01*
X446950Y241645D01*
Y243255D01*
G01Y245550D02*
X450050D01*
X449430Y245090D01*
G01X446950D02*
Y246010D01*
G01X448242Y247922D02*
X448603Y248190D01*
X448810Y248420D01*
X448913Y248727D01*
X448810Y248995D01*
X448603Y249187D01*
X448293Y249340D01*
X447932Y249378D01*
X447622Y249340D01*
X447312Y249187D01*
X447053Y248957D01*
X446950Y248688D01*
X447053Y248382D01*
X447363Y248113D01*
X447828Y247960D01*
X448345Y247922D01*
X449017Y247998D01*
X449378Y248113D01*
X449740Y248305D01*
X449998Y248573D01*
X450050Y248842D01*
X449947Y249110D01*
X449688Y249302D01*
G01X439917Y296466D02*
Y299566D01*
X438958D01*
X438652Y299411D01*
X438460Y299204D01*
X438383Y298791D01*
X438460Y298378D01*
X438690Y298119D01*
X438958Y297964D01*
X439917D01*
G01X438958D02*
X438383Y296466D01*
G01X436778Y299049D02*
X436548Y299359D01*
X436280Y299514D01*
X435973Y299566D01*
X435590Y299463D01*
X435322Y299204D01*
X435245Y298894D01*
X435283Y298584D01*
X435437Y298326D01*
X436203Y297809D01*
X436548Y297448D01*
X436778Y296931D01*
X436855Y296466D01*
X435245D01*
G01X433602Y296828D02*
X433333Y296569D01*
X433027Y296466D01*
X432720Y296569D01*
X432452Y296879D01*
X432260Y297344D01*
X432183Y297809D01*
Y298378D01*
X432260Y298843D01*
X432452Y299256D01*
X432682Y299463D01*
X432950Y299566D01*
X433257Y299463D01*
X433487Y299256D01*
X433640Y298946D01*
X433717Y298533D01*
X433640Y298171D01*
X433448Y297809D01*
X433218Y297603D01*
X432950Y297551D01*
X432643Y297654D01*
X432413Y297913D01*
X432183Y298378D01*
G01X430693Y296931D02*
X430463Y296673D01*
X430195Y296518D01*
X429850Y296466D01*
X429505Y296569D01*
X429237Y296776D01*
X429045Y297138D01*
X429007Y297551D01*
X429083Y297964D01*
X429275Y298223D01*
X429543Y298429D01*
X429812Y298481D01*
X430080Y298429D01*
X430425Y298223D01*
X430310Y299566D01*
X429275D01*
G01X442917Y384950D02*
Y388050D01*
X441958D01*
X441652Y387895D01*
X441460Y387688D01*
X441383Y387275D01*
X441460Y386862D01*
X441690Y386603D01*
X441958Y386448D01*
X442917D01*
G01X441958D02*
X441383Y384950D01*
G01X439893Y385570D02*
X439663Y385208D01*
X439357Y385002D01*
X439012Y384950D01*
X438705Y385002D01*
X438398Y385260D01*
X438207Y385570D01*
X438168Y385880D01*
X438245Y386242D01*
X438513Y386500D01*
X438782Y386603D01*
X439127D01*
G01X438782D02*
X438552Y386758D01*
X438360Y387017D01*
X438283Y387327D01*
X438360Y387637D01*
X438552Y387895D01*
X438897Y388050D01*
X439242Y387998D01*
X439587Y387792D01*
G01X435950Y384950D02*
Y388050D01*
X436410Y387430D01*
G01Y384950D02*
X435490D01*
G01X433502Y385312D02*
X433233Y385053D01*
X432927Y384950D01*
X432620Y385053D01*
X432352Y385363D01*
X432160Y385828D01*
X432083Y386293D01*
Y386862D01*
X432160Y387327D01*
X432352Y387740D01*
X432582Y387947D01*
X432850Y388050D01*
X433157Y387947D01*
X433387Y387740D01*
X433540Y387430D01*
X433617Y387017D01*
X433540Y386655D01*
X433348Y386293D01*
X433118Y386087D01*
X432850Y386035D01*
X432543Y386138D01*
X432313Y386397D01*
X432083Y386862D01*
G01X441307Y397792D02*
X441537Y397947D01*
X441805Y398050D01*
X442112D01*
X442457Y397895D01*
X442725Y397637D01*
X442917Y397327D01*
X443070Y396810D01*
X443108Y396345D01*
X443032Y395880D01*
X442917Y395570D01*
X442687Y395260D01*
X442418Y395053D01*
X442150Y394950D01*
X441882D01*
X441613Y395053D01*
X441383Y395208D01*
X441192Y395415D01*
G01X439893Y395570D02*
X439663Y395208D01*
X439357Y395002D01*
X439012Y394950D01*
X438705Y395002D01*
X438398Y395260D01*
X438207Y395570D01*
X438168Y395880D01*
X438245Y396242D01*
X438513Y396500D01*
X438782Y396603D01*
X439127D01*
G01X438782D02*
X438552Y396758D01*
X438360Y397017D01*
X438283Y397327D01*
X438360Y397637D01*
X438552Y397895D01*
X438897Y398050D01*
X439242Y397998D01*
X439587Y397792D01*
G01X435950Y394950D02*
Y398050D01*
X436410Y397430D01*
G01Y394950D02*
X435490D01*
G01X433693Y395415D02*
X433463Y395157D01*
X433195Y395002D01*
X432850Y394950D01*
X432505Y395053D01*
X432237Y395260D01*
X432045Y395622D01*
X432007Y396035D01*
X432083Y396448D01*
X432275Y396707D01*
X432543Y396913D01*
X432812Y396965D01*
X433080Y396913D01*
X433425Y396707D01*
X433310Y398050D01*
X432275D01*
G01X442917Y405982D02*
Y409082D01*
X441958D01*
X441652Y408927D01*
X441460Y408720D01*
X441383Y408307D01*
X441460Y407894D01*
X441690Y407635D01*
X441958Y407480D01*
X442917D01*
G01X441958D02*
X441383Y405982D01*
G01X439893Y406602D02*
X439663Y406240D01*
X439357Y406034D01*
X439012Y405982D01*
X438705Y406034D01*
X438398Y406292D01*
X438207Y406602D01*
X438168Y406912D01*
X438245Y407274D01*
X438513Y407532D01*
X438782Y407635D01*
X439127D01*
G01X438782D02*
X438552Y407790D01*
X438360Y408049D01*
X438283Y408359D01*
X438360Y408669D01*
X438552Y408927D01*
X438897Y409082D01*
X439242Y409030D01*
X439587Y408824D01*
G01X436678Y408565D02*
X436448Y408875D01*
X436180Y409030D01*
X435873Y409082D01*
X435490Y408979D01*
X435222Y408720D01*
X435145Y408410D01*
X435183Y408100D01*
X435337Y407842D01*
X436103Y407325D01*
X436448Y406964D01*
X436678Y406447D01*
X436755Y405982D01*
X435145D01*
G01X432850D02*
Y409082D01*
X433310Y408462D01*
G01Y405982D02*
X432390D01*
G01X442917Y410982D02*
Y414082D01*
X441958D01*
X441652Y413927D01*
X441460Y413720D01*
X441383Y413307D01*
X441460Y412894D01*
X441690Y412635D01*
X441958Y412480D01*
X442917D01*
G01X441958D02*
X441383Y410982D01*
G01X439893Y411602D02*
X439663Y411240D01*
X439357Y411034D01*
X439012Y410982D01*
X438705Y411034D01*
X438398Y411292D01*
X438207Y411602D01*
X438168Y411912D01*
X438245Y412274D01*
X438513Y412532D01*
X438782Y412635D01*
X439127D01*
G01X438782D02*
X438552Y412790D01*
X438360Y413049D01*
X438283Y413359D01*
X438360Y413669D01*
X438552Y413927D01*
X438897Y414082D01*
X439242Y414030D01*
X439587Y413824D01*
G01X436678Y413565D02*
X436448Y413875D01*
X436180Y414030D01*
X435873Y414082D01*
X435490Y413979D01*
X435222Y413720D01*
X435145Y413410D01*
X435183Y413100D01*
X435337Y412842D01*
X436103Y412325D01*
X436448Y411964D01*
X436678Y411447D01*
X436755Y410982D01*
X435145D01*
G01X433578Y413565D02*
X433348Y413875D01*
X433080Y414030D01*
X432773Y414082D01*
X432390Y413979D01*
X432122Y413720D01*
X432045Y413410D01*
X432083Y413100D01*
X432237Y412842D01*
X433003Y412325D01*
X433348Y411964D01*
X433578Y411447D01*
X433655Y410982D01*
X432045D01*
G01X451966Y110583D02*
X455066D01*
Y111542D01*
X454911Y111848D01*
X454704Y112040D01*
X454291Y112117D01*
X453878Y112040D01*
X453619Y111810D01*
X453464Y111542D01*
Y110583D01*
G01Y111542D02*
X451966Y112117D01*
G01Y114910D02*
X455066D01*
X452844Y113492D01*
Y115408D01*
G01X451966Y118010D02*
X455066D01*
X452844Y116592D01*
Y118508D01*
G01X455066Y120650D02*
X454963Y120343D01*
X454704Y120113D01*
X454394Y119960D01*
X453981Y119845D01*
X453516Y119807D01*
X453051Y119845D01*
X452638Y119960D01*
X452328Y120113D01*
X452069Y120343D01*
X451966Y120650D01*
X452069Y120957D01*
X452328Y121187D01*
X452638Y121340D01*
X453051Y121455D01*
X453516Y121493D01*
X453981Y121455D01*
X454394Y121340D01*
X454704Y121187D01*
X454963Y120957D01*
X455066Y120650D01*
G01X457466Y110583D02*
X460566D01*
Y111542D01*
X460411Y111848D01*
X460204Y112040D01*
X459791Y112117D01*
X459378Y112040D01*
X459119Y111810D01*
X458964Y111542D01*
Y110583D01*
G01Y111542D02*
X457466Y112117D01*
G01Y114910D02*
X460566D01*
X458344Y113492D01*
Y115408D01*
G01X457466Y118010D02*
X460566D01*
X458344Y116592D01*
Y118508D01*
G01X457466Y120650D02*
X460566D01*
X459946Y120190D01*
G01X457466D02*
Y121110D01*
G01X467413Y128190D02*
Y131290D01*
X466454D01*
X466148Y131135D01*
X465956Y130928D01*
X465879Y130515D01*
X465956Y130102D01*
X466186Y129843D01*
X466454Y129688D01*
X467413D01*
G01X466454D02*
X465879Y128190D01*
G01X464274Y130773D02*
X464044Y131083D01*
X463776Y131238D01*
X463469Y131290D01*
X463086Y131187D01*
X462818Y130928D01*
X462741Y130618D01*
X462779Y130308D01*
X462933Y130050D01*
X463699Y129533D01*
X464044Y129172D01*
X464274Y128655D01*
X464351Y128190D01*
X462741D01*
G01X460523D02*
X460446Y128862D01*
X460331Y129430D01*
X460178Y129947D01*
X459986Y130515D01*
X459679Y131290D01*
X461213D01*
G01X458189Y128655D02*
X457959Y128397D01*
X457691Y128242D01*
X457346Y128190D01*
X457001Y128293D01*
X456733Y128500D01*
X456541Y128862D01*
X456503Y129275D01*
X456579Y129688D01*
X456771Y129947D01*
X457039Y130153D01*
X457308Y130205D01*
X457576Y130153D01*
X457921Y129947D01*
X457806Y131290D01*
X456771D01*
G01X452896Y136353D02*
X453021Y136193D01*
X453104Y136006D01*
Y135793D01*
X452979Y135553D01*
X452771Y135366D01*
X452521Y135233D01*
X452104Y135126D01*
X451729Y135099D01*
X451354Y135153D01*
X451104Y135233D01*
X450854Y135393D01*
X450687Y135579D01*
X450604Y135766D01*
Y135953D01*
X450687Y136139D01*
X450812Y136299D01*
X450979Y136433D01*
G01X450604Y137966D02*
X453104D01*
X452604Y137646D01*
G01X450604D02*
Y138286D01*
G01X451646Y139659D02*
X451937Y139846D01*
X452104Y140006D01*
X452187Y140219D01*
X452104Y140406D01*
X451937Y140539D01*
X451687Y140646D01*
X451396Y140673D01*
X451146Y140646D01*
X450896Y140539D01*
X450687Y140379D01*
X450604Y140193D01*
X450687Y139979D01*
X450937Y139793D01*
X451312Y139686D01*
X451729Y139659D01*
X452271Y139713D01*
X452562Y139793D01*
X452854Y139926D01*
X453062Y140113D01*
X453104Y140299D01*
X453021Y140486D01*
X452812Y140619D01*
G01X453104Y142366D02*
X453021Y142153D01*
X452812Y141993D01*
X452562Y141886D01*
X452229Y141806D01*
X451854Y141779D01*
X451479Y141806D01*
X451146Y141886D01*
X450896Y141993D01*
X450687Y142153D01*
X450604Y142366D01*
X450687Y142579D01*
X450896Y142739D01*
X451146Y142846D01*
X451479Y142926D01*
X451854Y142953D01*
X452229Y142926D01*
X452562Y142846D01*
X452812Y142739D01*
X453021Y142579D01*
X453104Y142366D01*
G01X463713Y141792D02*
X463873Y141917D01*
X464060Y142000D01*
X464273D01*
X464513Y141875D01*
X464700Y141667D01*
X464833Y141417D01*
X464940Y141000D01*
X464967Y140625D01*
X464913Y140250D01*
X464833Y140000D01*
X464673Y139750D01*
X464487Y139583D01*
X464300Y139500D01*
X464113D01*
X463927Y139583D01*
X463767Y139708D01*
X463633Y139875D01*
G01X462100Y139500D02*
Y142000D01*
X462420Y141500D01*
G01Y139500D02*
X461780D01*
G01X460407Y141583D02*
X460247Y141833D01*
X460060Y141958D01*
X459847Y142000D01*
X459580Y141917D01*
X459393Y141708D01*
X459340Y141458D01*
X459367Y141208D01*
X459473Y141000D01*
X460007Y140583D01*
X460247Y140292D01*
X460407Y139875D01*
X460460Y139500D01*
X459340D01*
G01X457753D02*
X457700Y140042D01*
X457620Y140500D01*
X457513Y140917D01*
X457380Y141375D01*
X457167Y142000D01*
X458233D01*
G01X454019Y143941D02*
Y146441D01*
X453353D01*
X453139Y146316D01*
X453006Y146149D01*
X452953Y145816D01*
X453006Y145483D01*
X453166Y145274D01*
X453353Y145149D01*
X454019D01*
G01X453353D02*
X452953Y143941D01*
G01X451793Y146024D02*
X451633Y146274D01*
X451446Y146399D01*
X451233Y146441D01*
X450966Y146358D01*
X450779Y146149D01*
X450726Y145899D01*
X450753Y145649D01*
X450859Y145441D01*
X451393Y145024D01*
X451633Y144733D01*
X451793Y144316D01*
X451846Y143941D01*
X450726D01*
G01X449139D02*
X449086Y144483D01*
X449006Y144941D01*
X448899Y145358D01*
X448766Y145816D01*
X448553Y146441D01*
X449619D01*
G01X446886Y143941D02*
X446699Y143983D01*
X446486Y144108D01*
X446353Y144316D01*
X446299Y144608D01*
X446353Y144899D01*
X446513Y145149D01*
X446753Y145274D01*
X447019D01*
X447179Y145358D01*
X447313Y145566D01*
X447366Y145858D01*
X447286Y146149D01*
X447099Y146358D01*
X446886Y146441D01*
X446673Y146358D01*
X446486Y146149D01*
X446406Y145858D01*
X446459Y145566D01*
X446593Y145358D01*
X446753Y145274D01*
X447019D01*
X447259Y145149D01*
X447419Y144899D01*
X447473Y144608D01*
X447419Y144316D01*
X447286Y144108D01*
X447073Y143983D01*
X446886Y143941D01*
G01X460770Y153203D02*
X460895Y153043D01*
X460978Y152856D01*
Y152643D01*
X460853Y152403D01*
X460645Y152216D01*
X460395Y152083D01*
X459978Y151976D01*
X459603Y151949D01*
X459228Y152003D01*
X458978Y152083D01*
X458728Y152243D01*
X458561Y152429D01*
X458478Y152616D01*
Y152803D01*
X458561Y152989D01*
X458686Y153149D01*
X458853Y153283D01*
G01X458770Y154363D02*
X458561Y154549D01*
X458478Y154763D01*
X458561Y154976D01*
X458811Y155163D01*
X459186Y155296D01*
X459561Y155349D01*
X460020D01*
X460395Y155296D01*
X460728Y155163D01*
X460895Y155003D01*
X460978Y154816D01*
X460895Y154603D01*
X460728Y154443D01*
X460478Y154336D01*
X460145Y154283D01*
X459853Y154336D01*
X459561Y154469D01*
X459395Y154629D01*
X459353Y154816D01*
X459436Y155029D01*
X459645Y155189D01*
X460020Y155349D01*
G01X458978Y156429D02*
X458686Y156589D01*
X458520Y156803D01*
X458478Y157043D01*
X458520Y157256D01*
X458728Y157469D01*
X458978Y157603D01*
X459228Y157629D01*
X459520Y157576D01*
X459728Y157389D01*
X459811Y157203D01*
Y156963D01*
G01Y157203D02*
X459936Y157363D01*
X460145Y157496D01*
X460395Y157549D01*
X460645Y157496D01*
X460853Y157363D01*
X460978Y157123D01*
X460936Y156883D01*
X460770Y156643D01*
G01X453292Y164787D02*
X453417Y164627D01*
X453500Y164440D01*
Y164227D01*
X453375Y163987D01*
X453167Y163800D01*
X452917Y163667D01*
X452500Y163560D01*
X452125Y163533D01*
X451750Y163587D01*
X451500Y163667D01*
X451250Y163827D01*
X451083Y164013D01*
X451000Y164200D01*
Y164387D01*
X451083Y164573D01*
X451208Y164733D01*
X451375Y164867D01*
G01X453083Y165893D02*
X453333Y166053D01*
X453458Y166240D01*
X453500Y166453D01*
X453417Y166720D01*
X453208Y166907D01*
X452958Y166960D01*
X452708Y166933D01*
X452500Y166827D01*
X452083Y166293D01*
X451792Y166053D01*
X451375Y165893D01*
X451000Y165840D01*
Y166960D01*
G01X453500Y168600D02*
X453417Y168387D01*
X453208Y168227D01*
X452958Y168120D01*
X452625Y168040D01*
X452250Y168013D01*
X451875Y168040D01*
X451542Y168120D01*
X451292Y168227D01*
X451083Y168387D01*
X451000Y168600D01*
X451083Y168813D01*
X451292Y168973D01*
X451542Y169080D01*
X451875Y169160D01*
X452250Y169187D01*
X452625Y169160D01*
X452958Y169080D01*
X453208Y168973D01*
X453417Y168813D01*
X453500Y168600D01*
G01X451000Y170747D02*
X451542Y170800D01*
X452000Y170880D01*
X452417Y170987D01*
X452875Y171120D01*
X453500Y171333D01*
Y170267D01*
G01X449459Y154539D02*
X449584Y154379D01*
X449667Y154192D01*
Y153979D01*
X449542Y153739D01*
X449334Y153552D01*
X449084Y153419D01*
X448667Y153312D01*
X448292Y153285D01*
X447917Y153339D01*
X447667Y153419D01*
X447417Y153579D01*
X447250Y153765D01*
X447167Y153952D01*
Y154139D01*
X447250Y154325D01*
X447375Y154485D01*
X447542Y154619D01*
G01X447167Y156152D02*
X449667D01*
X449167Y155832D01*
G01X447167D02*
Y156472D01*
G01X447542Y157765D02*
X447334Y157925D01*
X447209Y158112D01*
X447167Y158352D01*
X447250Y158592D01*
X447417Y158779D01*
X447709Y158912D01*
X448042Y158939D01*
X448375Y158885D01*
X448584Y158752D01*
X448750Y158565D01*
X448792Y158379D01*
X448750Y158192D01*
X448584Y157952D01*
X449667Y158032D01*
Y158752D01*
G01X449250Y160045D02*
X449500Y160205D01*
X449625Y160392D01*
X449667Y160605D01*
X449584Y160872D01*
X449375Y161059D01*
X449125Y161112D01*
X448875Y161085D01*
X448667Y160979D01*
X448250Y160445D01*
X447959Y160205D01*
X447542Y160045D01*
X447167Y159992D01*
Y161112D01*
G01X457213Y176542D02*
X457373Y176667D01*
X457560Y176750D01*
X457773D01*
X458013Y176625D01*
X458200Y176417D01*
X458333Y176167D01*
X458440Y175750D01*
X458467Y175375D01*
X458413Y175000D01*
X458333Y174750D01*
X458173Y174500D01*
X457987Y174333D01*
X457800Y174250D01*
X457613D01*
X457427Y174333D01*
X457267Y174458D01*
X457133Y174625D01*
G01X455600Y174250D02*
Y176750D01*
X455920Y176250D01*
G01Y174250D02*
X455280D01*
G01X453907Y175292D02*
X453720Y175583D01*
X453560Y175750D01*
X453347Y175833D01*
X453160Y175750D01*
X453027Y175583D01*
X452920Y175333D01*
X452893Y175042D01*
X452920Y174792D01*
X453027Y174542D01*
X453187Y174333D01*
X453373Y174250D01*
X453587Y174333D01*
X453773Y174583D01*
X453880Y174958D01*
X453907Y175375D01*
X453853Y175917D01*
X453773Y176208D01*
X453640Y176500D01*
X453453Y176708D01*
X453267Y176750D01*
X453080Y176667D01*
X452947Y176458D01*
G01X451787Y174625D02*
X451627Y174417D01*
X451440Y174292D01*
X451200Y174250D01*
X450960Y174333D01*
X450773Y174500D01*
X450640Y174792D01*
X450613Y175125D01*
X450667Y175458D01*
X450800Y175667D01*
X450987Y175833D01*
X451173Y175875D01*
X451360Y175833D01*
X451600Y175667D01*
X451520Y176750D01*
X450800D01*
G01X469833Y174466D02*
Y176966D01*
X469167D01*
X468953Y176841D01*
X468820Y176674D01*
X468767Y176341D01*
X468820Y176008D01*
X468980Y175799D01*
X469167Y175674D01*
X469833D01*
G01X469167D02*
X468767Y174466D01*
G01X467687Y174841D02*
X467527Y174633D01*
X467340Y174508D01*
X467100Y174466D01*
X466860Y174549D01*
X466673Y174716D01*
X466540Y175008D01*
X466513Y175341D01*
X466567Y175674D01*
X466700Y175883D01*
X466887Y176049D01*
X467073Y176091D01*
X467260Y176049D01*
X467500Y175883D01*
X467420Y176966D01*
X466700D01*
G01X464900D02*
X465113Y176883D01*
X465273Y176674D01*
X465380Y176424D01*
X465460Y176091D01*
X465487Y175716D01*
X465460Y175341D01*
X465380Y175008D01*
X465273Y174758D01*
X465113Y174549D01*
X464900Y174466D01*
X464687Y174549D01*
X464527Y174758D01*
X464420Y175008D01*
X464340Y175341D01*
X464313Y175716D01*
X464340Y176091D01*
X464420Y176424D01*
X464527Y176674D01*
X464687Y176883D01*
X464900Y176966D01*
G01X462700Y174466D02*
Y176966D01*
X463020Y176466D01*
G01Y174466D02*
X462380D01*
G01X463713Y169542D02*
X463873Y169667D01*
X464060Y169750D01*
X464273D01*
X464513Y169625D01*
X464700Y169417D01*
X464833Y169167D01*
X464940Y168750D01*
X464967Y168375D01*
X464913Y168000D01*
X464833Y167750D01*
X464673Y167500D01*
X464487Y167333D01*
X464300Y167250D01*
X464113D01*
X463927Y167333D01*
X463767Y167458D01*
X463633Y167625D01*
G01X462607Y169333D02*
X462447Y169583D01*
X462260Y169708D01*
X462047Y169750D01*
X461780Y169667D01*
X461593Y169458D01*
X461540Y169208D01*
X461567Y168958D01*
X461673Y168750D01*
X462207Y168333D01*
X462447Y168042D01*
X462607Y167625D01*
X462660Y167250D01*
X461540D01*
G01X459900D02*
Y169750D01*
X460220Y169250D01*
G01Y167250D02*
X459580D01*
G01X457700Y169750D02*
X457913Y169667D01*
X458073Y169458D01*
X458180Y169208D01*
X458260Y168875D01*
X458287Y168500D01*
X458260Y168125D01*
X458180Y167792D01*
X458073Y167542D01*
X457913Y167333D01*
X457700Y167250D01*
X457487Y167333D01*
X457327Y167542D01*
X457220Y167792D01*
X457140Y168125D01*
X457113Y168500D01*
X457140Y168875D01*
X457220Y169208D01*
X457327Y169458D01*
X457487Y169667D01*
X457700Y169750D01*
G01X468647Y181148D02*
X468807Y181273D01*
X468994Y181356D01*
X469207D01*
X469447Y181231D01*
X469634Y181023D01*
X469767Y180773D01*
X469874Y180356D01*
X469901Y179981D01*
X469847Y179606D01*
X469767Y179356D01*
X469607Y179106D01*
X469421Y178939D01*
X469234Y178856D01*
X469047D01*
X468861Y178939D01*
X468701Y179064D01*
X468567Y179231D01*
G01X467034Y178856D02*
Y181356D01*
X467354Y180856D01*
G01Y178856D02*
X466714D01*
G01X465421Y179356D02*
X465261Y179064D01*
X465047Y178898D01*
X464807Y178856D01*
X464594Y178898D01*
X464381Y179106D01*
X464247Y179356D01*
X464221Y179606D01*
X464274Y179898D01*
X464461Y180106D01*
X464647Y180189D01*
X464887D01*
G01X464647D02*
X464487Y180314D01*
X464354Y180523D01*
X464301Y180773D01*
X464354Y181023D01*
X464487Y181231D01*
X464727Y181356D01*
X464967Y181314D01*
X465207Y181148D01*
G01X463087Y179148D02*
X462901Y178939D01*
X462687Y178856D01*
X462474Y178939D01*
X462287Y179189D01*
X462154Y179564D01*
X462101Y179939D01*
Y180398D01*
X462154Y180773D01*
X462287Y181106D01*
X462447Y181273D01*
X462634Y181356D01*
X462847Y181273D01*
X463007Y181106D01*
X463114Y180856D01*
X463167Y180523D01*
X463114Y180231D01*
X462981Y179939D01*
X462821Y179773D01*
X462634Y179731D01*
X462421Y179814D01*
X462261Y180023D01*
X462101Y180398D01*
G01X453042Y179787D02*
X453167Y179627D01*
X453250Y179440D01*
Y179227D01*
X453125Y178987D01*
X452917Y178800D01*
X452667Y178667D01*
X452250Y178560D01*
X451875Y178533D01*
X451500Y178587D01*
X451250Y178667D01*
X451000Y178827D01*
X450833Y179013D01*
X450750Y179200D01*
Y179387D01*
X450833Y179573D01*
X450958Y179733D01*
X451125Y179867D01*
G01X450750Y181400D02*
X453250D01*
X452750Y181080D01*
G01X450750D02*
Y181720D01*
G01X453250Y183600D02*
X453167Y183387D01*
X452958Y183227D01*
X452708Y183120D01*
X452375Y183040D01*
X452000Y183013D01*
X451625Y183040D01*
X451292Y183120D01*
X451042Y183227D01*
X450833Y183387D01*
X450750Y183600D01*
X450833Y183813D01*
X451042Y183973D01*
X451292Y184080D01*
X451625Y184160D01*
X452000Y184187D01*
X452375Y184160D01*
X452708Y184080D01*
X452958Y183973D01*
X453167Y183813D01*
X453250Y183600D01*
G01X450750Y185747D02*
X451292Y185800D01*
X451750Y185880D01*
X452167Y185987D01*
X452625Y186120D01*
X453250Y186333D01*
Y185267D01*
G01X447183Y178541D02*
X449683D01*
Y179207D01*
X449558Y179421D01*
X449391Y179554D01*
X449058Y179607D01*
X448725Y179554D01*
X448516Y179394D01*
X448391Y179207D01*
Y178541D01*
G01Y179207D02*
X447183Y179607D01*
G01Y181594D02*
X449683D01*
X447891Y180607D01*
Y181941D01*
G01X447683Y182887D02*
X447391Y183047D01*
X447225Y183261D01*
X447183Y183501D01*
X447225Y183714D01*
X447433Y183927D01*
X447683Y184061D01*
X447933Y184087D01*
X448225Y184034D01*
X448433Y183847D01*
X448516Y183661D01*
Y183421D01*
G01Y183661D02*
X448641Y183821D01*
X448850Y183954D01*
X449100Y184007D01*
X449350Y183954D01*
X449558Y183821D01*
X449683Y183581D01*
X449641Y183341D01*
X449475Y183101D01*
G01X447183Y185621D02*
X447725Y185674D01*
X448183Y185754D01*
X448600Y185861D01*
X449058Y185994D01*
X449683Y186207D01*
Y185141D01*
G01X465804Y197446D02*
X466034Y197601D01*
X466302Y197704D01*
X466609D01*
X466954Y197549D01*
X467222Y197291D01*
X467414Y196981D01*
X467567Y196464D01*
X467605Y195999D01*
X467529Y195534D01*
X467414Y195224D01*
X467184Y194914D01*
X466915Y194707D01*
X466647Y194604D01*
X466379D01*
X466110Y194707D01*
X465880Y194862D01*
X465689Y195069D01*
G01X463547Y194604D02*
Y197704D01*
X464007Y197084D01*
G01Y194604D02*
X463087D01*
G01X461290Y195224D02*
X461060Y194862D01*
X460754Y194656D01*
X460409Y194604D01*
X460102Y194656D01*
X459795Y194914D01*
X459604Y195224D01*
X459565Y195534D01*
X459642Y195896D01*
X459910Y196154D01*
X460179Y196257D01*
X460524D01*
G01X460179D02*
X459949Y196412D01*
X459757Y196671D01*
X459680Y196981D01*
X459757Y197291D01*
X459949Y197549D01*
X460294Y197704D01*
X460639Y197652D01*
X460984Y197446D01*
G01X457347Y197704D02*
X457654Y197601D01*
X457884Y197342D01*
X458037Y197032D01*
X458152Y196619D01*
X458190Y196154D01*
X458152Y195689D01*
X458037Y195276D01*
X457884Y194966D01*
X457654Y194707D01*
X457347Y194604D01*
X457040Y194707D01*
X456810Y194966D01*
X456657Y195276D01*
X456542Y195689D01*
X456504Y196154D01*
X456542Y196619D01*
X456657Y197032D01*
X456810Y197342D01*
X457040Y197601D01*
X457347Y197704D01*
G01X464710Y192959D02*
X464870Y193084D01*
X465057Y193167D01*
X465270D01*
X465510Y193042D01*
X465697Y192834D01*
X465830Y192584D01*
X465937Y192167D01*
X465964Y191792D01*
X465910Y191417D01*
X465830Y191167D01*
X465670Y190917D01*
X465484Y190750D01*
X465297Y190667D01*
X465110D01*
X464924Y190750D01*
X464764Y190875D01*
X464630Y191042D01*
G01X463604Y192750D02*
X463444Y193000D01*
X463257Y193125D01*
X463044Y193167D01*
X462777Y193084D01*
X462590Y192875D01*
X462537Y192625D01*
X462564Y192375D01*
X462670Y192167D01*
X463204Y191750D01*
X463444Y191459D01*
X463604Y191042D01*
X463657Y190667D01*
X462537D01*
G01X460897D02*
Y193167D01*
X461217Y192667D01*
G01Y190667D02*
X460577D01*
G01X459284Y191042D02*
X459124Y190834D01*
X458937Y190709D01*
X458697Y190667D01*
X458457Y190750D01*
X458270Y190917D01*
X458137Y191209D01*
X458110Y191542D01*
X458164Y191875D01*
X458297Y192084D01*
X458484Y192250D01*
X458670Y192292D01*
X458857Y192250D01*
X459097Y192084D01*
X459017Y193167D01*
X458297D01*
G01X465542Y183287D02*
X465667Y183127D01*
X465750Y182940D01*
Y182727D01*
X465625Y182487D01*
X465417Y182300D01*
X465167Y182167D01*
X464750Y182060D01*
X464375Y182033D01*
X464000Y182087D01*
X463750Y182167D01*
X463500Y182327D01*
X463333Y182513D01*
X463250Y182700D01*
Y182887D01*
X463333Y183073D01*
X463458Y183233D01*
X463625Y183367D01*
G01X465333Y184393D02*
X465583Y184553D01*
X465708Y184740D01*
X465750Y184953D01*
X465667Y185220D01*
X465458Y185407D01*
X465208Y185460D01*
X464958Y185433D01*
X464750Y185327D01*
X464333Y184793D01*
X464042Y184553D01*
X463625Y184393D01*
X463250Y184340D01*
Y185460D01*
G01X465750Y187100D02*
X465667Y186887D01*
X465458Y186727D01*
X465208Y186620D01*
X464875Y186540D01*
X464500Y186513D01*
X464125Y186540D01*
X463792Y186620D01*
X463542Y186727D01*
X463333Y186887D01*
X463250Y187100D01*
X463333Y187313D01*
X463542Y187473D01*
X463792Y187580D01*
X464125Y187660D01*
X464500Y187687D01*
X464875Y187660D01*
X465208Y187580D01*
X465458Y187473D01*
X465667Y187313D01*
X465750Y187100D01*
G01X465333Y188793D02*
X465583Y188953D01*
X465708Y189140D01*
X465750Y189353D01*
X465667Y189620D01*
X465458Y189807D01*
X465208Y189860D01*
X464958Y189833D01*
X464750Y189727D01*
X464333Y189193D01*
X464042Y188953D01*
X463625Y188793D01*
X463250Y188740D01*
Y189860D01*
G01X450292Y191693D02*
X450447Y191463D01*
X450550Y191195D01*
Y190888D01*
X450395Y190543D01*
X450137Y190275D01*
X449827Y190083D01*
X449310Y189930D01*
X448845Y189892D01*
X448380Y189968D01*
X448070Y190083D01*
X447760Y190313D01*
X447553Y190582D01*
X447450Y190850D01*
Y191118D01*
X447553Y191387D01*
X447708Y191617D01*
X447915Y191808D01*
G01X447450Y193950D02*
X450550D01*
X449930Y193490D01*
G01X447450D02*
Y194410D01*
G01X450033Y196322D02*
X450343Y196552D01*
X450498Y196820D01*
X450550Y197127D01*
X450447Y197510D01*
X450188Y197778D01*
X449878Y197855D01*
X449568Y197817D01*
X449310Y197663D01*
X448793Y196897D01*
X448432Y196552D01*
X447915Y196322D01*
X447450Y196245D01*
Y197855D01*
G01X448742Y199422D02*
X449103Y199690D01*
X449310Y199920D01*
X449413Y200227D01*
X449310Y200495D01*
X449103Y200687D01*
X448793Y200840D01*
X448432Y200878D01*
X448122Y200840D01*
X447812Y200687D01*
X447553Y200457D01*
X447450Y200188D01*
X447553Y199882D01*
X447863Y199613D01*
X448328Y199460D01*
X448845Y199422D01*
X449517Y199498D01*
X449878Y199613D01*
X450240Y199805D01*
X450498Y200073D01*
X450550Y200342D01*
X450447Y200610D01*
X450188Y200802D01*
G01X461892Y183309D02*
Y185809D01*
X461226D01*
X461012Y185684D01*
X460879Y185517D01*
X460826Y185184D01*
X460879Y184851D01*
X461039Y184642D01*
X461226Y184517D01*
X461892D01*
G01X461226D02*
X460826Y183309D01*
G01X459746Y183684D02*
X459586Y183476D01*
X459399Y183351D01*
X459159Y183309D01*
X458919Y183392D01*
X458732Y183559D01*
X458599Y183851D01*
X458572Y184184D01*
X458626Y184517D01*
X458759Y184726D01*
X458946Y184892D01*
X459132Y184934D01*
X459319Y184892D01*
X459559Y184726D01*
X459479Y185809D01*
X458759D01*
G01X456959D02*
X457172Y185726D01*
X457332Y185517D01*
X457439Y185267D01*
X457519Y184934D01*
X457546Y184559D01*
X457519Y184184D01*
X457439Y183851D01*
X457332Y183601D01*
X457172Y183392D01*
X456959Y183309D01*
X456746Y183392D01*
X456586Y183601D01*
X456479Y183851D01*
X456399Y184184D01*
X456372Y184559D01*
X456399Y184934D01*
X456479Y185267D01*
X456586Y185517D01*
X456746Y185726D01*
X456959Y185809D01*
G01X455266Y185392D02*
X455106Y185642D01*
X454919Y185767D01*
X454706Y185809D01*
X454439Y185726D01*
X454252Y185517D01*
X454199Y185267D01*
X454226Y185017D01*
X454332Y184809D01*
X454866Y184392D01*
X455106Y184101D01*
X455266Y183684D01*
X455319Y183309D01*
X454199D01*
G01X461893Y187246D02*
Y189746D01*
X461227D01*
X461013Y189621D01*
X460880Y189454D01*
X460827Y189121D01*
X460880Y188788D01*
X461040Y188579D01*
X461227Y188454D01*
X461893D01*
G01X461227D02*
X460827Y187246D01*
G01X459667Y189329D02*
X459507Y189579D01*
X459320Y189704D01*
X459107Y189746D01*
X458840Y189663D01*
X458653Y189454D01*
X458600Y189204D01*
X458627Y188954D01*
X458733Y188746D01*
X459267Y188329D01*
X459507Y188038D01*
X459667Y187621D01*
X459720Y187246D01*
X458600D01*
G01X457013D02*
X456960Y187788D01*
X456880Y188246D01*
X456773Y188663D01*
X456640Y189121D01*
X456427Y189746D01*
X457493D01*
G01X454760D02*
X454973Y189663D01*
X455133Y189454D01*
X455240Y189204D01*
X455320Y188871D01*
X455347Y188496D01*
X455320Y188121D01*
X455240Y187788D01*
X455133Y187538D01*
X454973Y187329D01*
X454760Y187246D01*
X454547Y187329D01*
X454387Y187538D01*
X454280Y187788D01*
X454200Y188121D01*
X454173Y188496D01*
X454200Y188871D01*
X454280Y189204D01*
X454387Y189454D01*
X454547Y189663D01*
X454760Y189746D01*
G01X460450Y238583D02*
X463550D01*
Y239542D01*
X463395Y239848D01*
X463188Y240040D01*
X462775Y240117D01*
X462362Y240040D01*
X462103Y239810D01*
X461948Y239542D01*
Y238583D01*
G01Y239542D02*
X460450Y240117D01*
G01X463033Y241722D02*
X463343Y241952D01*
X463498Y242220D01*
X463550Y242527D01*
X463447Y242910D01*
X463188Y243178D01*
X462878Y243255D01*
X462568Y243217D01*
X462310Y243063D01*
X461793Y242297D01*
X461432Y241952D01*
X460915Y241722D01*
X460450Y241645D01*
Y243255D01*
G01X463033Y244822D02*
X463343Y245052D01*
X463498Y245320D01*
X463550Y245627D01*
X463447Y246010D01*
X463188Y246278D01*
X462878Y246355D01*
X462568Y246317D01*
X462310Y246163D01*
X461793Y245397D01*
X461432Y245052D01*
X460915Y244822D01*
X460450Y244745D01*
Y246355D01*
G01Y249110D02*
X463550D01*
X461328Y247692D01*
Y249608D01*
G01X455950Y238583D02*
X459050D01*
Y239542D01*
X458895Y239848D01*
X458688Y240040D01*
X458275Y240117D01*
X457862Y240040D01*
X457603Y239810D01*
X457448Y239542D01*
Y238583D01*
G01Y239542D02*
X455950Y240117D01*
G01X458533Y241722D02*
X458843Y241952D01*
X458998Y242220D01*
X459050Y242527D01*
X458947Y242910D01*
X458688Y243178D01*
X458378Y243255D01*
X458068Y243217D01*
X457810Y243063D01*
X457293Y242297D01*
X456932Y241952D01*
X456415Y241722D01*
X455950Y241645D01*
Y243255D01*
G01X458533Y244822D02*
X458843Y245052D01*
X458998Y245320D01*
X459050Y245627D01*
X458947Y246010D01*
X458688Y246278D01*
X458378Y246355D01*
X458068Y246317D01*
X457810Y246163D01*
X457293Y245397D01*
X456932Y245052D01*
X456415Y244822D01*
X455950Y244745D01*
Y246355D01*
G01X456570Y247807D02*
X456208Y248037D01*
X456002Y248343D01*
X455950Y248688D01*
X456002Y248995D01*
X456260Y249302D01*
X456570Y249493D01*
X456880Y249532D01*
X457242Y249455D01*
X457500Y249187D01*
X457603Y248918D01*
Y248573D01*
G01Y248918D02*
X457758Y249148D01*
X458017Y249340D01*
X458327Y249417D01*
X458637Y249340D01*
X458895Y249148D01*
X459050Y248803D01*
X458998Y248458D01*
X458792Y248113D01*
G01X451450Y238583D02*
X454550D01*
Y239542D01*
X454395Y239848D01*
X454188Y240040D01*
X453775Y240117D01*
X453362Y240040D01*
X453103Y239810D01*
X452948Y239542D01*
Y238583D01*
G01Y239542D02*
X451450Y240117D01*
G01X454033Y241722D02*
X454343Y241952D01*
X454498Y242220D01*
X454550Y242527D01*
X454447Y242910D01*
X454188Y243178D01*
X453878Y243255D01*
X453568Y243217D01*
X453310Y243063D01*
X452793Y242297D01*
X452432Y241952D01*
X451915Y241722D01*
X451450Y241645D01*
Y243255D01*
G01Y245550D02*
X454550D01*
X453930Y245090D01*
G01X451450D02*
Y246010D01*
G01X451915Y247807D02*
X451657Y248037D01*
X451502Y248305D01*
X451450Y248650D01*
X451553Y248995D01*
X451760Y249263D01*
X452122Y249455D01*
X452535Y249493D01*
X452948Y249417D01*
X453207Y249225D01*
X453413Y248957D01*
X453465Y248688D01*
X453413Y248420D01*
X453207Y248075D01*
X454550Y248190D01*
Y249225D01*
G01X458307Y285792D02*
X458537Y285947D01*
X458805Y286050D01*
X459112D01*
X459457Y285895D01*
X459725Y285637D01*
X459917Y285327D01*
X460070Y284810D01*
X460108Y284345D01*
X460032Y283880D01*
X459917Y283570D01*
X459687Y283260D01*
X459418Y283053D01*
X459150Y282950D01*
X458882D01*
X458613Y283053D01*
X458383Y283208D01*
X458192Y283415D01*
G01X456778Y285533D02*
X456548Y285843D01*
X456280Y285998D01*
X455973Y286050D01*
X455590Y285947D01*
X455322Y285688D01*
X455245Y285378D01*
X455283Y285068D01*
X455437Y284810D01*
X456203Y284293D01*
X456548Y283932D01*
X456778Y283415D01*
X456855Y282950D01*
X455245D01*
G01X453678Y285533D02*
X453448Y285843D01*
X453180Y285998D01*
X452873Y286050D01*
X452490Y285947D01*
X452222Y285688D01*
X452145Y285378D01*
X452183Y285068D01*
X452337Y284810D01*
X453103Y284293D01*
X453448Y283932D01*
X453678Y283415D01*
X453755Y282950D01*
X452145D01*
G01X450502Y283312D02*
X450233Y283053D01*
X449927Y282950D01*
X449620Y283053D01*
X449352Y283363D01*
X449160Y283828D01*
X449083Y284293D01*
Y284862D01*
X449160Y285327D01*
X449352Y285740D01*
X449582Y285947D01*
X449850Y286050D01*
X450157Y285947D01*
X450387Y285740D01*
X450540Y285430D01*
X450617Y285017D01*
X450540Y284655D01*
X450348Y284293D01*
X450118Y284087D01*
X449850Y284035D01*
X449543Y284138D01*
X449313Y284397D01*
X449083Y284862D01*
G01X459917Y277950D02*
Y281050D01*
X458958D01*
X458652Y280895D01*
X458460Y280688D01*
X458383Y280275D01*
X458460Y279862D01*
X458690Y279603D01*
X458958Y279448D01*
X459917D01*
G01X458958D02*
X458383Y277950D01*
G01X456778Y280533D02*
X456548Y280843D01*
X456280Y280998D01*
X455973Y281050D01*
X455590Y280947D01*
X455322Y280688D01*
X455245Y280378D01*
X455283Y280068D01*
X455437Y279810D01*
X456203Y279293D01*
X456548Y278932D01*
X456778Y278415D01*
X456855Y277950D01*
X455245D01*
G01X453678Y279242D02*
X453410Y279603D01*
X453180Y279810D01*
X452873Y279913D01*
X452605Y279810D01*
X452413Y279603D01*
X452260Y279293D01*
X452222Y278932D01*
X452260Y278622D01*
X452413Y278312D01*
X452643Y278053D01*
X452912Y277950D01*
X453218Y278053D01*
X453487Y278363D01*
X453640Y278828D01*
X453678Y279345D01*
X453602Y280017D01*
X453487Y280378D01*
X453295Y280740D01*
X453027Y280998D01*
X452758Y281050D01*
X452490Y280947D01*
X452298Y280688D01*
G01X449850Y281050D02*
X450157Y280947D01*
X450387Y280688D01*
X450540Y280378D01*
X450655Y279965D01*
X450693Y279500D01*
X450655Y279035D01*
X450540Y278622D01*
X450387Y278312D01*
X450157Y278053D01*
X449850Y277950D01*
X449543Y278053D01*
X449313Y278312D01*
X449160Y278622D01*
X449045Y279035D01*
X449007Y279500D01*
X449045Y279965D01*
X449160Y280378D01*
X449313Y280688D01*
X449543Y280947D01*
X449850Y281050D01*
G01X458307Y290792D02*
X458537Y290947D01*
X458805Y291050D01*
X459112D01*
X459457Y290895D01*
X459725Y290637D01*
X459917Y290327D01*
X460070Y289810D01*
X460108Y289345D01*
X460032Y288880D01*
X459917Y288570D01*
X459687Y288260D01*
X459418Y288053D01*
X459150Y287950D01*
X458882D01*
X458613Y288053D01*
X458383Y288208D01*
X458192Y288415D01*
G01X456778Y290533D02*
X456548Y290843D01*
X456280Y290998D01*
X455973Y291050D01*
X455590Y290947D01*
X455322Y290688D01*
X455245Y290378D01*
X455283Y290068D01*
X455437Y289810D01*
X456203Y289293D01*
X456548Y288932D01*
X456778Y288415D01*
X456855Y287950D01*
X455245D01*
G01X453602Y288312D02*
X453333Y288053D01*
X453027Y287950D01*
X452720Y288053D01*
X452452Y288363D01*
X452260Y288828D01*
X452183Y289293D01*
Y289862D01*
X452260Y290327D01*
X452452Y290740D01*
X452682Y290947D01*
X452950Y291050D01*
X453257Y290947D01*
X453487Y290740D01*
X453640Y290430D01*
X453717Y290017D01*
X453640Y289655D01*
X453448Y289293D01*
X453218Y289087D01*
X452950Y289035D01*
X452643Y289138D01*
X452413Y289397D01*
X452183Y289862D01*
G01X449390Y287950D02*
Y291050D01*
X450808Y288828D01*
X448892D01*
G01X459917Y292950D02*
Y296050D01*
X458958D01*
X458652Y295895D01*
X458460Y295688D01*
X458383Y295275D01*
X458460Y294862D01*
X458690Y294603D01*
X458958Y294448D01*
X459917D01*
G01X458958D02*
X458383Y292950D01*
G01X456778Y295533D02*
X456548Y295843D01*
X456280Y295998D01*
X455973Y296050D01*
X455590Y295947D01*
X455322Y295688D01*
X455245Y295378D01*
X455283Y295068D01*
X455437Y294810D01*
X456203Y294293D01*
X456548Y293932D01*
X456778Y293415D01*
X456855Y292950D01*
X455245D01*
G01X453678Y295533D02*
X453448Y295843D01*
X453180Y295998D01*
X452873Y296050D01*
X452490Y295947D01*
X452222Y295688D01*
X452145Y295378D01*
X452183Y295068D01*
X452337Y294810D01*
X453103Y294293D01*
X453448Y293932D01*
X453678Y293415D01*
X453755Y292950D01*
X452145D01*
G01X450578Y294242D02*
X450310Y294603D01*
X450080Y294810D01*
X449773Y294913D01*
X449505Y294810D01*
X449313Y294603D01*
X449160Y294293D01*
X449122Y293932D01*
X449160Y293622D01*
X449313Y293312D01*
X449543Y293053D01*
X449812Y292950D01*
X450118Y293053D01*
X450387Y293363D01*
X450540Y293828D01*
X450578Y294345D01*
X450502Y295017D01*
X450387Y295378D01*
X450195Y295740D01*
X449927Y295998D01*
X449658Y296050D01*
X449390Y295947D01*
X449198Y295688D01*
G01X465757Y390792D02*
X465987Y390947D01*
X466255Y391050D01*
X466562D01*
X466907Y390895D01*
X467175Y390637D01*
X467367Y390327D01*
X467520Y389810D01*
X467558Y389345D01*
X467482Y388880D01*
X467367Y388570D01*
X467137Y388260D01*
X466868Y388053D01*
X466600Y387950D01*
X466332D01*
X466063Y388053D01*
X465833Y388208D01*
X465642Y388415D01*
G01X463500Y387950D02*
X463232Y388002D01*
X462925Y388157D01*
X462733Y388415D01*
X462657Y388777D01*
X462733Y389138D01*
X462963Y389448D01*
X463308Y389603D01*
X463692D01*
X463922Y389707D01*
X464113Y389965D01*
X464190Y390327D01*
X464075Y390688D01*
X463807Y390947D01*
X463500Y391050D01*
X463193Y390947D01*
X462925Y390688D01*
X462810Y390327D01*
X462887Y389965D01*
X463078Y389707D01*
X463308Y389603D01*
X463692D01*
X464037Y389448D01*
X464267Y389138D01*
X464343Y388777D01*
X464267Y388415D01*
X464075Y388157D01*
X463768Y388002D01*
X463500Y387950D01*
G01X460400Y391050D02*
X460707Y390947D01*
X460937Y390688D01*
X461090Y390378D01*
X461205Y389965D01*
X461243Y389500D01*
X461205Y389035D01*
X461090Y388622D01*
X460937Y388312D01*
X460707Y388053D01*
X460400Y387950D01*
X460093Y388053D01*
X459863Y388312D01*
X459710Y388622D01*
X459595Y389035D01*
X459557Y389500D01*
X459595Y389965D01*
X459710Y390378D01*
X459863Y390688D01*
X460093Y390947D01*
X460400Y391050D01*
G01X467307Y395292D02*
X467537Y395447D01*
X467805Y395550D01*
X468112D01*
X468457Y395395D01*
X468725Y395137D01*
X468917Y394827D01*
X469070Y394310D01*
X469108Y393845D01*
X469032Y393380D01*
X468917Y393070D01*
X468687Y392760D01*
X468418Y392553D01*
X468150Y392450D01*
X467882D01*
X467613Y392553D01*
X467383Y392708D01*
X467192Y392915D01*
G01X465778Y395033D02*
X465548Y395343D01*
X465280Y395498D01*
X464973Y395550D01*
X464590Y395447D01*
X464322Y395188D01*
X464245Y394878D01*
X464283Y394568D01*
X464437Y394310D01*
X465203Y393793D01*
X465548Y393432D01*
X465778Y392915D01*
X465855Y392450D01*
X464245D01*
G01X462027D02*
X461950Y393122D01*
X461835Y393690D01*
X461682Y394207D01*
X461490Y394775D01*
X461183Y395550D01*
X462717D01*
G01X459693Y393070D02*
X459463Y392708D01*
X459157Y392502D01*
X458812Y392450D01*
X458505Y392502D01*
X458198Y392760D01*
X458007Y393070D01*
X457968Y393380D01*
X458045Y393742D01*
X458313Y394000D01*
X458582Y394103D01*
X458927D01*
G01X458582D02*
X458352Y394258D01*
X458160Y394517D01*
X458083Y394827D01*
X458160Y395137D01*
X458352Y395395D01*
X458697Y395550D01*
X459042Y395498D01*
X459387Y395292D01*
G01X476917Y90466D02*
Y93566D01*
X475958D01*
X475652Y93411D01*
X475460Y93204D01*
X475383Y92791D01*
X475460Y92378D01*
X475690Y92119D01*
X475958Y91964D01*
X476917D01*
G01X475958D02*
X475383Y90466D01*
G01X472590D02*
Y93566D01*
X474008Y91344D01*
X472092D01*
G01X469950Y90466D02*
X469682Y90518D01*
X469375Y90673D01*
X469183Y90931D01*
X469107Y91293D01*
X469183Y91654D01*
X469413Y91964D01*
X469758Y92119D01*
X470142D01*
X470372Y92223D01*
X470563Y92481D01*
X470640Y92843D01*
X470525Y93204D01*
X470257Y93463D01*
X469950Y93566D01*
X469643Y93463D01*
X469375Y93204D01*
X469260Y92843D01*
X469337Y92481D01*
X469528Y92223D01*
X469758Y92119D01*
X470142D01*
X470487Y91964D01*
X470717Y91654D01*
X470793Y91293D01*
X470717Y90931D01*
X470525Y90673D01*
X470218Y90518D01*
X469950Y90466D01*
G01X467693Y91086D02*
X467463Y90724D01*
X467157Y90518D01*
X466812Y90466D01*
X466505Y90518D01*
X466198Y90776D01*
X466007Y91086D01*
X465968Y91396D01*
X466045Y91758D01*
X466313Y92016D01*
X466582Y92119D01*
X466927D01*
G01X466582D02*
X466352Y92274D01*
X466160Y92533D01*
X466083Y92843D01*
X466160Y93153D01*
X466352Y93411D01*
X466697Y93566D01*
X467042Y93514D01*
X467387Y93308D01*
G01X476917Y95466D02*
Y98566D01*
X475958D01*
X475652Y98411D01*
X475460Y98204D01*
X475383Y97791D01*
X475460Y97378D01*
X475690Y97119D01*
X475958Y96964D01*
X476917D01*
G01X475958D02*
X475383Y95466D01*
G01X472590D02*
Y98566D01*
X474008Y96344D01*
X472092D01*
G01X469950Y95466D02*
X469682Y95518D01*
X469375Y95673D01*
X469183Y95931D01*
X469107Y96293D01*
X469183Y96654D01*
X469413Y96964D01*
X469758Y97119D01*
X470142D01*
X470372Y97223D01*
X470563Y97481D01*
X470640Y97843D01*
X470525Y98204D01*
X470257Y98463D01*
X469950Y98566D01*
X469643Y98463D01*
X469375Y98204D01*
X469260Y97843D01*
X469337Y97481D01*
X469528Y97223D01*
X469758Y97119D01*
X470142D01*
X470487Y96964D01*
X470717Y96654D01*
X470793Y96293D01*
X470717Y95931D01*
X470525Y95673D01*
X470218Y95518D01*
X469950Y95466D01*
G01X467578Y98049D02*
X467348Y98359D01*
X467080Y98514D01*
X466773Y98566D01*
X466390Y98463D01*
X466122Y98204D01*
X466045Y97894D01*
X466083Y97584D01*
X466237Y97326D01*
X467003Y96809D01*
X467348Y96448D01*
X467578Y95931D01*
X467655Y95466D01*
X466045D01*
G01X477958Y137029D02*
X478113Y136799D01*
X478216Y136531D01*
Y136224D01*
X478061Y135879D01*
X477803Y135611D01*
X477493Y135419D01*
X476976Y135266D01*
X476511Y135228D01*
X476046Y135304D01*
X475736Y135419D01*
X475426Y135649D01*
X475219Y135918D01*
X475116Y136186D01*
Y136454D01*
X475219Y136723D01*
X475374Y136953D01*
X475581Y137144D01*
G01X475116Y139286D02*
X478216D01*
X477596Y138826D01*
G01X475116D02*
Y139746D01*
G01X477699Y141658D02*
X478009Y141888D01*
X478164Y142156D01*
X478216Y142463D01*
X478113Y142846D01*
X477854Y143114D01*
X477544Y143191D01*
X477234Y143153D01*
X476976Y142999D01*
X476459Y142233D01*
X476098Y141888D01*
X475581Y141658D01*
X475116Y141581D01*
Y143191D01*
G01X477699Y144758D02*
X478009Y144988D01*
X478164Y145256D01*
X478216Y145563D01*
X478113Y145946D01*
X477854Y146214D01*
X477544Y146291D01*
X477234Y146253D01*
X476976Y146099D01*
X476459Y145333D01*
X476098Y144988D01*
X475581Y144758D01*
X475116Y144681D01*
Y146291D01*
G01X471213Y157792D02*
X471373Y157917D01*
X471560Y158000D01*
X471773D01*
X472013Y157875D01*
X472200Y157667D01*
X472333Y157417D01*
X472440Y157000D01*
X472467Y156625D01*
X472413Y156250D01*
X472333Y156000D01*
X472173Y155750D01*
X471987Y155583D01*
X471800Y155500D01*
X471613D01*
X471427Y155583D01*
X471267Y155708D01*
X471133Y155875D01*
G01X469600Y155500D02*
Y158000D01*
X469920Y157500D01*
G01Y155500D02*
X469280D01*
G01X467987Y155875D02*
X467827Y155667D01*
X467640Y155542D01*
X467400Y155500D01*
X467160Y155583D01*
X466973Y155750D01*
X466840Y156042D01*
X466813Y156375D01*
X466867Y156708D01*
X467000Y156917D01*
X467187Y157083D01*
X467373Y157125D01*
X467560Y157083D01*
X467800Y156917D01*
X467720Y158000D01*
X467000D01*
G01X465200Y155500D02*
Y158000D01*
X465520Y157500D01*
G01Y155500D02*
X464880D01*
G01X479292Y180404D02*
X479447Y180174D01*
X479550Y179906D01*
Y179599D01*
X479395Y179254D01*
X479137Y178986D01*
X478827Y178794D01*
X478310Y178641D01*
X477845Y178603D01*
X477380Y178679D01*
X477070Y178794D01*
X476760Y179024D01*
X476553Y179293D01*
X476450Y179561D01*
Y179829D01*
X476553Y180098D01*
X476708Y180328D01*
X476915Y180519D01*
G01X476450Y182661D02*
X479550D01*
X478930Y182201D01*
G01X476450D02*
Y183121D01*
G01Y186221D02*
X479550D01*
X477328Y184803D01*
Y186719D01*
G01X476915Y188018D02*
X476657Y188248D01*
X476502Y188516D01*
X476450Y188861D01*
X476553Y189206D01*
X476760Y189474D01*
X477122Y189666D01*
X477535Y189704D01*
X477948Y189628D01*
X478207Y189436D01*
X478413Y189168D01*
X478465Y188899D01*
X478413Y188631D01*
X478207Y188286D01*
X479550Y188401D01*
Y189436D01*
G01X473703Y167561D02*
Y170061D01*
X473037D01*
X472823Y169936D01*
X472690Y169769D01*
X472637Y169436D01*
X472690Y169103D01*
X472850Y168894D01*
X473037Y168769D01*
X473703D01*
G01X473037D02*
X472637Y167561D01*
G01X471557Y167936D02*
X471397Y167728D01*
X471210Y167603D01*
X470970Y167561D01*
X470730Y167644D01*
X470543Y167811D01*
X470410Y168103D01*
X470383Y168436D01*
X470437Y168769D01*
X470570Y168978D01*
X470757Y169144D01*
X470943Y169186D01*
X471130Y169144D01*
X471370Y168978D01*
X471290Y170061D01*
X470570D01*
G01X468770D02*
X468983Y169978D01*
X469143Y169769D01*
X469250Y169519D01*
X469330Y169186D01*
X469357Y168811D01*
X469330Y168436D01*
X469250Y168103D01*
X469143Y167853D01*
X468983Y167644D01*
X468770Y167561D01*
X468557Y167644D01*
X468397Y167853D01*
X468290Y168103D01*
X468210Y168436D01*
X468183Y168811D01*
X468210Y169186D01*
X468290Y169519D01*
X468397Y169769D01*
X468557Y169978D01*
X468770Y170061D01*
G01X466570D02*
X466783Y169978D01*
X466943Y169769D01*
X467050Y169519D01*
X467130Y169186D01*
X467157Y168811D01*
X467130Y168436D01*
X467050Y168103D01*
X466943Y167853D01*
X466783Y167644D01*
X466570Y167561D01*
X466357Y167644D01*
X466197Y167853D01*
X466090Y168103D01*
X466010Y168436D01*
X465983Y168811D01*
X466010Y169186D01*
X466090Y169519D01*
X466197Y169769D01*
X466357Y169978D01*
X466570Y170061D01*
G01X477615Y201383D02*
X477845Y201538D01*
X478113Y201641D01*
X478420D01*
X478765Y201486D01*
X479033Y201228D01*
X479225Y200918D01*
X479378Y200401D01*
X479416Y199936D01*
X479340Y199471D01*
X479225Y199161D01*
X478995Y198851D01*
X478726Y198644D01*
X478458Y198541D01*
X478190D01*
X477921Y198644D01*
X477691Y198799D01*
X477500Y199006D01*
G01X475358Y198541D02*
Y201641D01*
X475818Y201021D01*
G01Y198541D02*
X474898D01*
G01X472258Y201641D02*
X472565Y201538D01*
X472795Y201279D01*
X472948Y200969D01*
X473063Y200556D01*
X473101Y200091D01*
X473063Y199626D01*
X472948Y199213D01*
X472795Y198903D01*
X472565Y198644D01*
X472258Y198541D01*
X471951Y198644D01*
X471721Y198903D01*
X471568Y199213D01*
X471453Y199626D01*
X471415Y200091D01*
X471453Y200556D01*
X471568Y200969D01*
X471721Y201279D01*
X471951Y201538D01*
X472258Y201641D01*
G01X470001Y199161D02*
X469771Y198799D01*
X469465Y198593D01*
X469120Y198541D01*
X468813Y198593D01*
X468506Y198851D01*
X468315Y199161D01*
X468276Y199471D01*
X468353Y199833D01*
X468621Y200091D01*
X468890Y200194D01*
X469235D01*
G01X468890D02*
X468660Y200349D01*
X468468Y200608D01*
X468391Y200918D01*
X468468Y201228D01*
X468660Y201486D01*
X469005Y201641D01*
X469350Y201589D01*
X469695Y201383D01*
G01X467250Y182667D02*
X469750D01*
Y183333D01*
X469625Y183547D01*
X469458Y183680D01*
X469125Y183733D01*
X468792Y183680D01*
X468583Y183520D01*
X468458Y183333D01*
Y182667D01*
G01Y183333D02*
X467250Y183733D01*
G01X469333Y184893D02*
X469583Y185053D01*
X469708Y185240D01*
X469750Y185453D01*
X469667Y185720D01*
X469458Y185907D01*
X469208Y185960D01*
X468958Y185933D01*
X468750Y185827D01*
X468333Y185293D01*
X468042Y185053D01*
X467625Y184893D01*
X467250Y184840D01*
Y185960D01*
G01Y187547D02*
X467792Y187600D01*
X468250Y187680D01*
X468667Y187787D01*
X469125Y187920D01*
X469750Y188133D01*
Y187067D01*
G01X467250Y189800D02*
X469750D01*
X469250Y189480D01*
G01X467250D02*
Y190120D01*
G01X469192Y213064D02*
X469347Y212834D01*
X469450Y212566D01*
Y212259D01*
X469295Y211914D01*
X469037Y211646D01*
X468727Y211454D01*
X468210Y211301D01*
X467745Y211263D01*
X467280Y211339D01*
X466970Y211454D01*
X466660Y211684D01*
X466453Y211953D01*
X466350Y212221D01*
Y212489D01*
X466453Y212758D01*
X466608Y212988D01*
X466815Y213179D01*
G01X466350Y215321D02*
X469450D01*
X468830Y214861D01*
G01X466350D02*
Y215781D01*
G01X466815Y217578D02*
X466557Y217808D01*
X466402Y218076D01*
X466350Y218421D01*
X466453Y218766D01*
X466660Y219034D01*
X467022Y219226D01*
X467435Y219264D01*
X467848Y219188D01*
X468107Y218996D01*
X468313Y218728D01*
X468365Y218459D01*
X468313Y218191D01*
X468107Y217846D01*
X469450Y217961D01*
Y218996D01*
G01X466350Y221981D02*
X469450D01*
X467228Y220563D01*
Y222479D01*
G01X470805Y211454D02*
X473905D01*
Y212413D01*
X473750Y212719D01*
X473543Y212911D01*
X473130Y212988D01*
X472717Y212911D01*
X472458Y212681D01*
X472303Y212413D01*
Y211454D01*
G01Y212413D02*
X470805Y212988D01*
G01X471270Y214478D02*
X471012Y214708D01*
X470857Y214976D01*
X470805Y215321D01*
X470908Y215666D01*
X471115Y215934D01*
X471477Y216126D01*
X471890Y216164D01*
X472303Y216088D01*
X472562Y215896D01*
X472768Y215628D01*
X472820Y215359D01*
X472768Y215091D01*
X472562Y214746D01*
X473905Y214861D01*
Y215896D01*
G01Y218421D02*
X473802Y218114D01*
X473543Y217884D01*
X473233Y217731D01*
X472820Y217616D01*
X472355Y217578D01*
X471890Y217616D01*
X471477Y217731D01*
X471167Y217884D01*
X470908Y218114D01*
X470805Y218421D01*
X470908Y218728D01*
X471167Y218958D01*
X471477Y219111D01*
X471890Y219226D01*
X472355Y219264D01*
X472820Y219226D01*
X473233Y219111D01*
X473543Y218958D01*
X473802Y218728D01*
X473905Y218421D01*
G01X470805Y221981D02*
X473905D01*
X471683Y220563D01*
Y222479D01*
G01X474917Y206450D02*
Y209550D01*
X473958D01*
X473652Y209395D01*
X473460Y209188D01*
X473383Y208775D01*
X473460Y208362D01*
X473690Y208103D01*
X473958Y207948D01*
X474917D01*
G01X473958D02*
X473383Y206450D01*
G01X471893Y206915D02*
X471663Y206657D01*
X471395Y206502D01*
X471050Y206450D01*
X470705Y206553D01*
X470437Y206760D01*
X470245Y207122D01*
X470207Y207535D01*
X470283Y207948D01*
X470475Y208207D01*
X470743Y208413D01*
X471012Y208465D01*
X471280Y208413D01*
X471625Y208207D01*
X471510Y209550D01*
X470475D01*
G01X467950D02*
X468257Y209447D01*
X468487Y209188D01*
X468640Y208878D01*
X468755Y208465D01*
X468793Y208000D01*
X468755Y207535D01*
X468640Y207122D01*
X468487Y206812D01*
X468257Y206553D01*
X467950Y206450D01*
X467643Y206553D01*
X467413Y206812D01*
X467260Y207122D01*
X467145Y207535D01*
X467107Y208000D01*
X467145Y208465D01*
X467260Y208878D01*
X467413Y209188D01*
X467643Y209447D01*
X467950Y209550D01*
G01X465693Y207070D02*
X465463Y206708D01*
X465157Y206502D01*
X464812Y206450D01*
X464505Y206502D01*
X464198Y206760D01*
X464007Y207070D01*
X463968Y207380D01*
X464045Y207742D01*
X464313Y208000D01*
X464582Y208103D01*
X464927D01*
G01X464582D02*
X464352Y208258D01*
X464160Y208517D01*
X464083Y208827D01*
X464160Y209137D01*
X464352Y209395D01*
X464697Y209550D01*
X465042Y209498D01*
X465387Y209292D01*
G01X477417Y353500D02*
Y356600D01*
X476458D01*
X476152Y356445D01*
X475960Y356238D01*
X475883Y355825D01*
X475960Y355412D01*
X476190Y355153D01*
X476458Y354998D01*
X477417D01*
G01X476458D02*
X475883Y353500D01*
G01X473550D02*
Y356600D01*
X474010Y355980D01*
G01Y353500D02*
X473090D01*
G01X470450D02*
Y356600D01*
X470910Y355980D01*
G01Y353500D02*
X469990D01*
G01X468193Y353965D02*
X467963Y353707D01*
X467695Y353552D01*
X467350Y353500D01*
X467005Y353603D01*
X466737Y353810D01*
X466545Y354172D01*
X466507Y354585D01*
X466583Y354998D01*
X466775Y355257D01*
X467043Y355463D01*
X467312Y355515D01*
X467580Y355463D01*
X467925Y355257D01*
X467810Y356600D01*
X466775D01*
G01X500407Y127592D02*
X500637Y127747D01*
X500905Y127850D01*
X501212D01*
X501557Y127695D01*
X501825Y127437D01*
X502017Y127127D01*
X502170Y126610D01*
X502208Y126145D01*
X502132Y125680D01*
X502017Y125370D01*
X501787Y125060D01*
X501518Y124853D01*
X501250Y124750D01*
X500982D01*
X500713Y124853D01*
X500483Y125008D01*
X500292Y125215D01*
G01X498150Y124750D02*
Y127850D01*
X498610Y127230D01*
G01Y124750D02*
X497690D01*
G01X495778Y126042D02*
X495510Y126403D01*
X495280Y126610D01*
X494973Y126713D01*
X494705Y126610D01*
X494513Y126403D01*
X494360Y126093D01*
X494322Y125732D01*
X494360Y125422D01*
X494513Y125112D01*
X494743Y124853D01*
X495012Y124750D01*
X495318Y124853D01*
X495587Y125163D01*
X495740Y125628D01*
X495778Y126145D01*
X495702Y126817D01*
X495587Y127178D01*
X495395Y127540D01*
X495127Y127798D01*
X494858Y127850D01*
X494590Y127747D01*
X494398Y127488D01*
G01X491950Y124750D02*
X491682Y124802D01*
X491375Y124957D01*
X491183Y125215D01*
X491107Y125577D01*
X491183Y125938D01*
X491413Y126248D01*
X491758Y126403D01*
X492142D01*
X492372Y126507D01*
X492563Y126765D01*
X492640Y127127D01*
X492525Y127488D01*
X492257Y127747D01*
X491950Y127850D01*
X491643Y127747D01*
X491375Y127488D01*
X491260Y127127D01*
X491337Y126765D01*
X491528Y126507D01*
X491758Y126403D01*
X492142D01*
X492487Y126248D01*
X492717Y125938D01*
X492793Y125577D01*
X492717Y125215D01*
X492525Y124957D01*
X492218Y124802D01*
X491950Y124750D01*
G01X495917Y161450D02*
Y164550D01*
X494958D01*
X494652Y164395D01*
X494460Y164188D01*
X494383Y163775D01*
X494460Y163362D01*
X494690Y163103D01*
X494958Y162948D01*
X495917D01*
G01X494958D02*
X494383Y161450D01*
G01X492778Y164033D02*
X492548Y164343D01*
X492280Y164498D01*
X491973Y164550D01*
X491590Y164447D01*
X491322Y164188D01*
X491245Y163878D01*
X491283Y163568D01*
X491437Y163310D01*
X492203Y162793D01*
X492548Y162432D01*
X492778Y161915D01*
X492855Y161450D01*
X491245D01*
G01X488950D02*
Y164550D01*
X489410Y163930D01*
G01Y161450D02*
X488490D01*
G01X485927D02*
X485850Y162122D01*
X485735Y162690D01*
X485582Y163207D01*
X485390Y163775D01*
X485083Y164550D01*
X486617D01*
G01X495917Y165950D02*
Y169050D01*
X494958D01*
X494652Y168895D01*
X494460Y168688D01*
X494383Y168275D01*
X494460Y167862D01*
X494690Y167603D01*
X494958Y167448D01*
X495917D01*
G01X494958D02*
X494383Y165950D01*
G01X492778Y168533D02*
X492548Y168843D01*
X492280Y168998D01*
X491973Y169050D01*
X491590Y168947D01*
X491322Y168688D01*
X491245Y168378D01*
X491283Y168068D01*
X491437Y167810D01*
X492203Y167293D01*
X492548Y166932D01*
X492778Y166415D01*
X492855Y165950D01*
X491245D01*
G01X488950D02*
Y169050D01*
X489410Y168430D01*
G01Y165950D02*
X488490D01*
G01X485850D02*
X485582Y166002D01*
X485275Y166157D01*
X485083Y166415D01*
X485007Y166777D01*
X485083Y167138D01*
X485313Y167448D01*
X485658Y167603D01*
X486042D01*
X486272Y167707D01*
X486463Y167965D01*
X486540Y168327D01*
X486425Y168688D01*
X486157Y168947D01*
X485850Y169050D01*
X485543Y168947D01*
X485275Y168688D01*
X485160Y168327D01*
X485237Y167965D01*
X485428Y167707D01*
X485658Y167603D01*
X486042D01*
X486387Y167448D01*
X486617Y167138D01*
X486693Y166777D01*
X486617Y166415D01*
X486425Y166157D01*
X486118Y166002D01*
X485850Y165950D01*
G01X495917Y174950D02*
Y178050D01*
X494958D01*
X494652Y177895D01*
X494460Y177688D01*
X494383Y177275D01*
X494460Y176862D01*
X494690Y176603D01*
X494958Y176448D01*
X495917D01*
G01X494958D02*
X494383Y174950D01*
G01X492778Y177533D02*
X492548Y177843D01*
X492280Y177998D01*
X491973Y178050D01*
X491590Y177947D01*
X491322Y177688D01*
X491245Y177378D01*
X491283Y177068D01*
X491437Y176810D01*
X492203Y176293D01*
X492548Y175932D01*
X492778Y175415D01*
X492855Y174950D01*
X491245D01*
G01X488950Y178050D02*
X489257Y177947D01*
X489487Y177688D01*
X489640Y177378D01*
X489755Y176965D01*
X489793Y176500D01*
X489755Y176035D01*
X489640Y175622D01*
X489487Y175312D01*
X489257Y175053D01*
X488950Y174950D01*
X488643Y175053D01*
X488413Y175312D01*
X488260Y175622D01*
X488145Y176035D01*
X488107Y176500D01*
X488145Y176965D01*
X488260Y177378D01*
X488413Y177688D01*
X488643Y177947D01*
X488950Y178050D01*
G01X486502Y175312D02*
X486233Y175053D01*
X485927Y174950D01*
X485620Y175053D01*
X485352Y175363D01*
X485160Y175828D01*
X485083Y176293D01*
Y176862D01*
X485160Y177327D01*
X485352Y177740D01*
X485582Y177947D01*
X485850Y178050D01*
X486157Y177947D01*
X486387Y177740D01*
X486540Y177430D01*
X486617Y177017D01*
X486540Y176655D01*
X486348Y176293D01*
X486118Y176087D01*
X485850Y176035D01*
X485543Y176138D01*
X485313Y176397D01*
X485083Y176862D01*
G01X495917Y179450D02*
Y182550D01*
X494958D01*
X494652Y182395D01*
X494460Y182188D01*
X494383Y181775D01*
X494460Y181362D01*
X494690Y181103D01*
X494958Y180948D01*
X495917D01*
G01X494958D02*
X494383Y179450D01*
G01X492050D02*
Y182550D01*
X492510Y181930D01*
G01Y179450D02*
X491590D01*
G01X489602Y179812D02*
X489333Y179553D01*
X489027Y179450D01*
X488720Y179553D01*
X488452Y179863D01*
X488260Y180328D01*
X488183Y180793D01*
Y181362D01*
X488260Y181827D01*
X488452Y182240D01*
X488682Y182447D01*
X488950Y182550D01*
X489257Y182447D01*
X489487Y182240D01*
X489640Y181930D01*
X489717Y181517D01*
X489640Y181155D01*
X489448Y180793D01*
X489218Y180587D01*
X488950Y180535D01*
X488643Y180638D01*
X488413Y180897D01*
X488183Y181362D01*
G01X486693Y179915D02*
X486463Y179657D01*
X486195Y179502D01*
X485850Y179450D01*
X485505Y179553D01*
X485237Y179760D01*
X485045Y180122D01*
X485007Y180535D01*
X485083Y180948D01*
X485275Y181207D01*
X485543Y181413D01*
X485812Y181465D01*
X486080Y181413D01*
X486425Y181207D01*
X486310Y182550D01*
X485275D01*
G01X495917Y195950D02*
Y199050D01*
X494958D01*
X494652Y198895D01*
X494460Y198688D01*
X494383Y198275D01*
X494460Y197862D01*
X494690Y197603D01*
X494958Y197448D01*
X495917D01*
G01X494958D02*
X494383Y195950D01*
G01X492778Y198533D02*
X492548Y198843D01*
X492280Y198998D01*
X491973Y199050D01*
X491590Y198947D01*
X491322Y198688D01*
X491245Y198378D01*
X491283Y198068D01*
X491437Y197810D01*
X492203Y197293D01*
X492548Y196932D01*
X492778Y196415D01*
X492855Y195950D01*
X491245D01*
G01X489678Y197242D02*
X489410Y197603D01*
X489180Y197810D01*
X488873Y197913D01*
X488605Y197810D01*
X488413Y197603D01*
X488260Y197293D01*
X488222Y196932D01*
X488260Y196622D01*
X488413Y196312D01*
X488643Y196053D01*
X488912Y195950D01*
X489218Y196053D01*
X489487Y196363D01*
X489640Y196828D01*
X489678Y197345D01*
X489602Y198017D01*
X489487Y198378D01*
X489295Y198740D01*
X489027Y198998D01*
X488758Y199050D01*
X488490Y198947D01*
X488298Y198688D01*
G01X486693Y196415D02*
X486463Y196157D01*
X486195Y196002D01*
X485850Y195950D01*
X485505Y196053D01*
X485237Y196260D01*
X485045Y196622D01*
X485007Y197035D01*
X485083Y197448D01*
X485275Y197707D01*
X485543Y197913D01*
X485812Y197965D01*
X486080Y197913D01*
X486425Y197707D01*
X486310Y199050D01*
X485275D01*
G01X494367Y184466D02*
Y187566D01*
X493408D01*
X493102Y187411D01*
X492910Y187204D01*
X492833Y186791D01*
X492910Y186378D01*
X493140Y186119D01*
X493408Y185964D01*
X494367D01*
G01X493408D02*
X492833Y184466D01*
G01X491152Y184828D02*
X490883Y184569D01*
X490577Y184466D01*
X490270Y184569D01*
X490002Y184879D01*
X489810Y185344D01*
X489733Y185809D01*
Y186378D01*
X489810Y186843D01*
X490002Y187256D01*
X490232Y187463D01*
X490500Y187566D01*
X490807Y187463D01*
X491037Y187256D01*
X491190Y186946D01*
X491267Y186533D01*
X491190Y186171D01*
X490998Y185809D01*
X490768Y185603D01*
X490500Y185551D01*
X490193Y185654D01*
X489963Y185913D01*
X489733Y186378D01*
G01X488128Y187049D02*
X487898Y187359D01*
X487630Y187514D01*
X487323Y187566D01*
X486940Y187463D01*
X486672Y187204D01*
X486595Y186894D01*
X486633Y186584D01*
X486787Y186326D01*
X487553Y185809D01*
X487898Y185448D01*
X488128Y184931D01*
X488205Y184466D01*
X486595D01*
G01X495917Y200950D02*
Y204050D01*
X494958D01*
X494652Y203895D01*
X494460Y203688D01*
X494383Y203275D01*
X494460Y202862D01*
X494690Y202603D01*
X494958Y202448D01*
X495917D01*
G01X494958D02*
X494383Y200950D01*
G01X492778Y203533D02*
X492548Y203843D01*
X492280Y203998D01*
X491973Y204050D01*
X491590Y203947D01*
X491322Y203688D01*
X491245Y203378D01*
X491283Y203068D01*
X491437Y202810D01*
X492203Y202293D01*
X492548Y201932D01*
X492778Y201415D01*
X492855Y200950D01*
X491245D01*
G01X489678Y202242D02*
X489410Y202603D01*
X489180Y202810D01*
X488873Y202913D01*
X488605Y202810D01*
X488413Y202603D01*
X488260Y202293D01*
X488222Y201932D01*
X488260Y201622D01*
X488413Y201312D01*
X488643Y201053D01*
X488912Y200950D01*
X489218Y201053D01*
X489487Y201363D01*
X489640Y201828D01*
X489678Y202345D01*
X489602Y203017D01*
X489487Y203378D01*
X489295Y203740D01*
X489027Y203998D01*
X488758Y204050D01*
X488490Y203947D01*
X488298Y203688D01*
G01X485390Y200950D02*
Y204050D01*
X486808Y201828D01*
X484892D01*
G01X494550Y265283D02*
X497650D01*
Y266242D01*
X497495Y266548D01*
X497288Y266740D01*
X496875Y266817D01*
X496462Y266740D01*
X496203Y266510D01*
X496048Y266242D01*
Y265283D01*
G01Y266242D02*
X494550Y266817D01*
G01Y269150D02*
X497650D01*
X497030Y268690D01*
G01X494550D02*
Y269610D01*
G01Y272173D02*
X495222Y272250D01*
X495790Y272365D01*
X496307Y272518D01*
X496875Y272710D01*
X497650Y273017D01*
Y271483D01*
G01X494550Y275810D02*
X497650D01*
X495428Y274392D01*
Y276308D01*
G01X486950Y349583D02*
X490050D01*
Y350542D01*
X489895Y350848D01*
X489688Y351040D01*
X489275Y351117D01*
X488862Y351040D01*
X488603Y350810D01*
X488448Y350542D01*
Y349583D01*
G01Y350542D02*
X486950Y351117D01*
G01Y353450D02*
X490050D01*
X489430Y352990D01*
G01X486950D02*
Y353910D01*
G01Y356550D02*
X490050D01*
X489430Y356090D01*
G01X486950D02*
Y357010D01*
G01Y359650D02*
X490050D01*
X489430Y359190D01*
G01X486950D02*
Y360110D01*
G01X496950Y349583D02*
X500050D01*
Y350542D01*
X499895Y350848D01*
X499688Y351040D01*
X499275Y351117D01*
X498862Y351040D01*
X498603Y350810D01*
X498448Y350542D01*
Y349583D01*
G01Y350542D02*
X496950Y351117D01*
G01Y353450D02*
X500050D01*
X499430Y352990D01*
G01X496950D02*
Y353910D01*
G01X500050Y356550D02*
X499947Y356243D01*
X499688Y356013D01*
X499378Y355860D01*
X498965Y355745D01*
X498500Y355707D01*
X498035Y355745D01*
X497622Y355860D01*
X497312Y356013D01*
X497053Y356243D01*
X496950Y356550D01*
X497053Y356857D01*
X497312Y357087D01*
X497622Y357240D01*
X498035Y357355D01*
X498500Y357393D01*
X498965Y357355D01*
X499378Y357240D01*
X499688Y357087D01*
X499947Y356857D01*
X500050Y356550D01*
G01X497312Y358998D02*
X497053Y359267D01*
X496950Y359573D01*
X497053Y359880D01*
X497363Y360148D01*
X497828Y360340D01*
X498293Y360417D01*
X498862D01*
X499327Y360340D01*
X499740Y360148D01*
X499947Y359918D01*
X500050Y359650D01*
X499947Y359343D01*
X499740Y359113D01*
X499430Y358960D01*
X499017Y358883D01*
X498655Y358960D01*
X498293Y359152D01*
X498087Y359382D01*
X498035Y359650D01*
X498138Y359957D01*
X498397Y360187D01*
X498862Y360417D01*
G01X506417Y343950D02*
Y347050D01*
X505458D01*
X505152Y346895D01*
X504960Y346688D01*
X504883Y346275D01*
X504960Y345862D01*
X505190Y345603D01*
X505458Y345448D01*
X506417D01*
G01X505458D02*
X504883Y343950D01*
G01X503278Y346533D02*
X503048Y346843D01*
X502780Y346998D01*
X502473Y347050D01*
X502090Y346947D01*
X501822Y346688D01*
X501745Y346378D01*
X501783Y346068D01*
X501937Y345810D01*
X502703Y345293D01*
X503048Y344932D01*
X503278Y344415D01*
X503355Y343950D01*
X501745D01*
G01X500178Y345242D02*
X499910Y345603D01*
X499680Y345810D01*
X499373Y345913D01*
X499105Y345810D01*
X498913Y345603D01*
X498760Y345293D01*
X498722Y344932D01*
X498760Y344622D01*
X498913Y344312D01*
X499143Y344053D01*
X499412Y343950D01*
X499718Y344053D01*
X499987Y344363D01*
X500140Y344828D01*
X500178Y345345D01*
X500102Y346017D01*
X499987Y346378D01*
X499795Y346740D01*
X499527Y346998D01*
X499258Y347050D01*
X498990Y346947D01*
X498798Y346688D01*
G01X497002Y344312D02*
X496733Y344053D01*
X496427Y343950D01*
X496120Y344053D01*
X495852Y344363D01*
X495660Y344828D01*
X495583Y345293D01*
Y345862D01*
X495660Y346327D01*
X495852Y346740D01*
X496082Y346947D01*
X496350Y347050D01*
X496657Y346947D01*
X496887Y346740D01*
X497040Y346430D01*
X497117Y346017D01*
X497040Y345655D01*
X496848Y345293D01*
X496618Y345087D01*
X496350Y345035D01*
X496043Y345138D01*
X495813Y345397D01*
X495583Y345862D01*
G01X491950Y349583D02*
X495050D01*
Y350542D01*
X494895Y350848D01*
X494688Y351040D01*
X494275Y351117D01*
X493862Y351040D01*
X493603Y350810D01*
X493448Y350542D01*
Y349583D01*
G01Y350542D02*
X491950Y351117D01*
G01Y353450D02*
X495050D01*
X494430Y352990D01*
G01X491950D02*
Y353910D01*
G01Y356550D02*
X495050D01*
X494430Y356090D01*
G01X491950D02*
Y357010D01*
G01X495050Y359650D02*
X494947Y359343D01*
X494688Y359113D01*
X494378Y358960D01*
X493965Y358845D01*
X493500Y358807D01*
X493035Y358845D01*
X492622Y358960D01*
X492312Y359113D01*
X492053Y359343D01*
X491950Y359650D01*
X492053Y359957D01*
X492312Y360187D01*
X492622Y360340D01*
X493035Y360455D01*
X493500Y360493D01*
X493965Y360455D01*
X494378Y360340D01*
X494688Y360187D01*
X494947Y359957D01*
X495050Y359650D01*
G01X508507Y246692D02*
X508737Y246847D01*
X509005Y246950D01*
X509312D01*
X509657Y246795D01*
X509925Y246537D01*
X510117Y246227D01*
X510270Y245710D01*
X510308Y245245D01*
X510232Y244780D01*
X510117Y244470D01*
X509887Y244160D01*
X509618Y243953D01*
X509350Y243850D01*
X509082D01*
X508813Y243953D01*
X508583Y244108D01*
X508392Y244315D01*
G01X506250Y243850D02*
Y246950D01*
X506710Y246330D01*
G01Y243850D02*
X505790D01*
G01X503150D02*
X502882Y243902D01*
X502575Y244057D01*
X502383Y244315D01*
X502307Y244677D01*
X502383Y245038D01*
X502613Y245348D01*
X502958Y245503D01*
X503342D01*
X503572Y245607D01*
X503763Y245865D01*
X503840Y246227D01*
X503725Y246588D01*
X503457Y246847D01*
X503150Y246950D01*
X502843Y246847D01*
X502575Y246588D01*
X502460Y246227D01*
X502537Y245865D01*
X502728Y245607D01*
X502958Y245503D01*
X503342D01*
X503687Y245348D01*
X503917Y245038D01*
X503993Y244677D01*
X503917Y244315D01*
X503725Y244057D01*
X503418Y243902D01*
X503150Y243850D01*
G01X500050D02*
Y246950D01*
X500510Y246330D01*
G01Y243850D02*
X499590D01*
G01X509792Y385243D02*
X509947Y385013D01*
X510050Y384745D01*
Y384438D01*
X509895Y384093D01*
X509637Y383825D01*
X509327Y383633D01*
X508810Y383480D01*
X508345Y383442D01*
X507880Y383518D01*
X507570Y383633D01*
X507260Y383863D01*
X507053Y384132D01*
X506950Y384400D01*
Y384668D01*
X507053Y384937D01*
X507208Y385167D01*
X507415Y385358D01*
G01X506950Y387423D02*
X507622Y387500D01*
X508190Y387615D01*
X508707Y387768D01*
X509275Y387960D01*
X510050Y388267D01*
Y386733D01*
G01X507570Y389757D02*
X507208Y389987D01*
X507002Y390293D01*
X506950Y390638D01*
X507002Y390945D01*
X507260Y391252D01*
X507570Y391443D01*
X507880Y391482D01*
X508242Y391405D01*
X508500Y391137D01*
X508603Y390868D01*
Y390523D01*
G01Y390868D02*
X508758Y391098D01*
X509017Y391290D01*
X509327Y391367D01*
X509637Y391290D01*
X509895Y391098D01*
X510050Y390753D01*
X509998Y390408D01*
X509792Y390063D01*
G01X504792Y385243D02*
X504947Y385013D01*
X505050Y384745D01*
Y384438D01*
X504895Y384093D01*
X504637Y383825D01*
X504327Y383633D01*
X503810Y383480D01*
X503345Y383442D01*
X502880Y383518D01*
X502570Y383633D01*
X502260Y383863D01*
X502053Y384132D01*
X501950Y384400D01*
Y384668D01*
X502053Y384937D01*
X502208Y385167D01*
X502415Y385358D01*
G01X501950Y387423D02*
X502622Y387500D01*
X503190Y387615D01*
X503707Y387768D01*
X504275Y387960D01*
X505050Y388267D01*
Y386733D01*
G01X501950Y390600D02*
X502002Y390868D01*
X502157Y391175D01*
X502415Y391367D01*
X502777Y391443D01*
X503138Y391367D01*
X503448Y391137D01*
X503603Y390792D01*
Y390408D01*
X503707Y390178D01*
X503965Y389987D01*
X504327Y389910D01*
X504688Y390025D01*
X504947Y390293D01*
X505050Y390600D01*
X504947Y390907D01*
X504688Y391175D01*
X504327Y391290D01*
X503965Y391213D01*
X503707Y391022D01*
X503603Y390792D01*
Y390408D01*
X503448Y390063D01*
X503138Y389833D01*
X502777Y389757D01*
X502415Y389833D01*
X502157Y390025D01*
X502002Y390332D01*
X501950Y390600D01*
G01X542917Y226000D02*
Y229100D01*
X541958D01*
X541652Y228945D01*
X541460Y228738D01*
X541383Y228325D01*
X541460Y227912D01*
X541690Y227653D01*
X541958Y227498D01*
X542917D01*
G01X541958D02*
X541383Y226000D01*
G01X539778Y228583D02*
X539548Y228893D01*
X539280Y229048D01*
X538973Y229100D01*
X538590Y228997D01*
X538322Y228738D01*
X538245Y228428D01*
X538283Y228118D01*
X538437Y227860D01*
X539203Y227343D01*
X539548Y226982D01*
X539778Y226465D01*
X539855Y226000D01*
X538245D01*
G01X535490D02*
Y229100D01*
X536908Y226878D01*
X534992D01*
G01X533693Y226620D02*
X533463Y226258D01*
X533157Y226052D01*
X532812Y226000D01*
X532505Y226052D01*
X532198Y226310D01*
X532007Y226620D01*
X531968Y226930D01*
X532045Y227292D01*
X532313Y227550D01*
X532582Y227653D01*
X532927D01*
G01X532582D02*
X532352Y227808D01*
X532160Y228067D01*
X532083Y228377D01*
X532160Y228687D01*
X532352Y228945D01*
X532697Y229100D01*
X533042Y229048D01*
X533387Y228842D01*
G01X526250Y257783D02*
X529350D01*
Y258742D01*
X529195Y259048D01*
X528988Y259240D01*
X528575Y259317D01*
X528162Y259240D01*
X527903Y259010D01*
X527748Y258742D01*
Y257783D01*
G01Y258742D02*
X526250Y259317D01*
G01Y261650D02*
X529350D01*
X528730Y261190D01*
G01X526250D02*
Y262110D01*
G01Y264750D02*
X526302Y265018D01*
X526457Y265325D01*
X526715Y265517D01*
X527077Y265593D01*
X527438Y265517D01*
X527748Y265287D01*
X527903Y264942D01*
Y264558D01*
X528007Y264328D01*
X528265Y264137D01*
X528627Y264060D01*
X528988Y264175D01*
X529247Y264443D01*
X529350Y264750D01*
X529247Y265057D01*
X528988Y265325D01*
X528627Y265440D01*
X528265Y265363D01*
X528007Y265172D01*
X527903Y264942D01*
Y264558D01*
X527748Y264213D01*
X527438Y263983D01*
X527077Y263907D01*
X526715Y263983D01*
X526457Y264175D01*
X526302Y264482D01*
X526250Y264750D01*
G01Y267850D02*
X526302Y268118D01*
X526457Y268425D01*
X526715Y268617D01*
X527077Y268693D01*
X527438Y268617D01*
X527748Y268387D01*
X527903Y268042D01*
Y267658D01*
X528007Y267428D01*
X528265Y267237D01*
X528627Y267160D01*
X528988Y267275D01*
X529247Y267543D01*
X529350Y267850D01*
X529247Y268157D01*
X528988Y268425D01*
X528627Y268540D01*
X528265Y268463D01*
X528007Y268272D01*
X527903Y268042D01*
Y267658D01*
X527748Y267313D01*
X527438Y267083D01*
X527077Y267007D01*
X526715Y267083D01*
X526457Y267275D01*
X526302Y267582D01*
X526250Y267850D01*
G01X530958Y345950D02*
X530000Y349050D01*
X529042Y345950D01*
G01X529387Y347035D02*
X530613D01*
G01X532892Y358443D02*
X533047Y358213D01*
X533150Y357945D01*
Y357638D01*
X532995Y357293D01*
X532737Y357025D01*
X532427Y356833D01*
X531910Y356680D01*
X531445Y356642D01*
X530980Y356718D01*
X530670Y356833D01*
X530360Y357063D01*
X530153Y357332D01*
X530050Y357600D01*
Y357868D01*
X530153Y358137D01*
X530308Y358367D01*
X530515Y358558D01*
G01X530050Y359933D02*
X533150D01*
Y360892D01*
X532995Y361198D01*
X532788Y361390D01*
X532375Y361467D01*
X531962Y361390D01*
X531703Y361160D01*
X531548Y360892D01*
Y359933D01*
G01Y360892D02*
X530050Y361467D01*
G01X530670Y362957D02*
X530308Y363187D01*
X530102Y363493D01*
X530050Y363838D01*
X530102Y364145D01*
X530360Y364452D01*
X530670Y364643D01*
X530980Y364682D01*
X531342Y364605D01*
X531600Y364337D01*
X531703Y364068D01*
Y363723D01*
G01Y364068D02*
X531858Y364298D01*
X532117Y364490D01*
X532427Y364567D01*
X532737Y364490D01*
X532995Y364298D01*
X533150Y363953D01*
X533098Y363608D01*
X532892Y363263D01*
G01X530657Y378292D02*
X530887Y378447D01*
X531155Y378550D01*
X531462D01*
X531807Y378395D01*
X532075Y378137D01*
X532267Y377827D01*
X532420Y377310D01*
X532458Y376845D01*
X532382Y376380D01*
X532267Y376070D01*
X532037Y375760D01*
X531768Y375553D01*
X531500Y375450D01*
X531232D01*
X530963Y375553D01*
X530733Y375708D01*
X530542Y375915D01*
G01X525750Y412584D02*
X528850D01*
Y413543D01*
X528695Y413849D01*
X528488Y414041D01*
X528075Y414118D01*
X527662Y414041D01*
X527403Y413811D01*
X527248Y413543D01*
Y412584D01*
G01Y413543D02*
X525750Y414118D01*
G01X528333Y415723D02*
X528643Y415953D01*
X528798Y416221D01*
X528850Y416528D01*
X528747Y416911D01*
X528488Y417179D01*
X528178Y417256D01*
X527868Y417218D01*
X527610Y417064D01*
X527093Y416298D01*
X526732Y415953D01*
X526215Y415723D01*
X525750Y415646D01*
Y417256D01*
G01Y419551D02*
X528850D01*
X528230Y419091D01*
G01X525750D02*
Y420011D01*
G01X528850Y422651D02*
X528747Y422344D01*
X528488Y422114D01*
X528178Y421961D01*
X527765Y421846D01*
X527300Y421808D01*
X526835Y421846D01*
X526422Y421961D01*
X526112Y422114D01*
X525853Y422344D01*
X525750Y422651D01*
X525853Y422958D01*
X526112Y423188D01*
X526422Y423341D01*
X526835Y423456D01*
X527300Y423494D01*
X527765Y423456D01*
X528178Y423341D01*
X528488Y423188D01*
X528747Y422958D01*
X528850Y422651D01*
G01X530750Y412584D02*
X533850D01*
Y413543D01*
X533695Y413849D01*
X533488Y414041D01*
X533075Y414118D01*
X532662Y414041D01*
X532403Y413811D01*
X532248Y413543D01*
Y412584D01*
G01Y413543D02*
X530750Y414118D01*
G01X533333Y415723D02*
X533643Y415953D01*
X533798Y416221D01*
X533850Y416528D01*
X533747Y416911D01*
X533488Y417179D01*
X533178Y417256D01*
X532868Y417218D01*
X532610Y417064D01*
X532093Y416298D01*
X531732Y415953D01*
X531215Y415723D01*
X530750Y415646D01*
Y417256D01*
G01X533850Y419551D02*
X533747Y419244D01*
X533488Y419014D01*
X533178Y418861D01*
X532765Y418746D01*
X532300Y418708D01*
X531835Y418746D01*
X531422Y418861D01*
X531112Y419014D01*
X530853Y419244D01*
X530750Y419551D01*
X530853Y419858D01*
X531112Y420088D01*
X531422Y420241D01*
X531835Y420356D01*
X532300Y420394D01*
X532765Y420356D01*
X533178Y420241D01*
X533488Y420088D01*
X533747Y419858D01*
X533850Y419551D01*
G01X530750Y422651D02*
X530802Y422919D01*
X530957Y423226D01*
X531215Y423418D01*
X531577Y423494D01*
X531938Y423418D01*
X532248Y423188D01*
X532403Y422843D01*
Y422459D01*
X532507Y422229D01*
X532765Y422038D01*
X533127Y421961D01*
X533488Y422076D01*
X533747Y422344D01*
X533850Y422651D01*
X533747Y422958D01*
X533488Y423226D01*
X533127Y423341D01*
X532765Y423264D01*
X532507Y423073D01*
X532403Y422843D01*
Y422459D01*
X532248Y422114D01*
X531938Y421884D01*
X531577Y421808D01*
X531215Y421884D01*
X530957Y422076D01*
X530802Y422383D01*
X530750Y422651D01*
G01X547917Y67450D02*
Y70550D01*
X546958D01*
X546652Y70395D01*
X546460Y70188D01*
X546383Y69775D01*
X546460Y69362D01*
X546690Y69103D01*
X546958Y68948D01*
X547917D01*
G01X546958D02*
X546383Y67450D01*
G01X544778Y70033D02*
X544548Y70343D01*
X544280Y70498D01*
X543973Y70550D01*
X543590Y70447D01*
X543322Y70188D01*
X543245Y69878D01*
X543283Y69568D01*
X543437Y69310D01*
X544203Y68793D01*
X544548Y68432D01*
X544778Y67915D01*
X544855Y67450D01*
X543245D01*
G01X541793Y68070D02*
X541563Y67708D01*
X541257Y67502D01*
X540912Y67450D01*
X540605Y67502D01*
X540298Y67760D01*
X540107Y68070D01*
X540068Y68380D01*
X540145Y68742D01*
X540413Y69000D01*
X540682Y69103D01*
X541027D01*
G01X540682D02*
X540452Y69258D01*
X540260Y69517D01*
X540183Y69827D01*
X540260Y70137D01*
X540452Y70395D01*
X540797Y70550D01*
X541142Y70498D01*
X541487Y70292D01*
G01X538693Y68070D02*
X538463Y67708D01*
X538157Y67502D01*
X537812Y67450D01*
X537505Y67502D01*
X537198Y67760D01*
X537007Y68070D01*
X536968Y68380D01*
X537045Y68742D01*
X537313Y69000D01*
X537582Y69103D01*
X537927D01*
G01X537582D02*
X537352Y69258D01*
X537160Y69517D01*
X537083Y69827D01*
X537160Y70137D01*
X537352Y70395D01*
X537697Y70550D01*
X538042Y70498D01*
X538387Y70292D01*
G01X547917Y62450D02*
Y65550D01*
X546958D01*
X546652Y65395D01*
X546460Y65188D01*
X546383Y64775D01*
X546460Y64362D01*
X546690Y64103D01*
X546958Y63948D01*
X547917D01*
G01X546958D02*
X546383Y62450D01*
G01X544778Y65033D02*
X544548Y65343D01*
X544280Y65498D01*
X543973Y65550D01*
X543590Y65447D01*
X543322Y65188D01*
X543245Y64878D01*
X543283Y64568D01*
X543437Y64310D01*
X544203Y63793D01*
X544548Y63432D01*
X544778Y62915D01*
X544855Y62450D01*
X543245D01*
G01X541793Y63070D02*
X541563Y62708D01*
X541257Y62502D01*
X540912Y62450D01*
X540605Y62502D01*
X540298Y62760D01*
X540107Y63070D01*
X540068Y63380D01*
X540145Y63742D01*
X540413Y64000D01*
X540682Y64103D01*
X541027D01*
G01X540682D02*
X540452Y64258D01*
X540260Y64517D01*
X540183Y64827D01*
X540260Y65137D01*
X540452Y65395D01*
X540797Y65550D01*
X541142Y65498D01*
X541487Y65292D01*
G01X537850Y65550D02*
X538157Y65447D01*
X538387Y65188D01*
X538540Y64878D01*
X538655Y64465D01*
X538693Y64000D01*
X538655Y63535D01*
X538540Y63122D01*
X538387Y62812D01*
X538157Y62553D01*
X537850Y62450D01*
X537543Y62553D01*
X537313Y62812D01*
X537160Y63122D01*
X537045Y63535D01*
X537007Y64000D01*
X537045Y64465D01*
X537160Y64878D01*
X537313Y65188D01*
X537543Y65447D01*
X537850Y65550D01*
G01X540292Y158693D02*
X540447Y158463D01*
X540550Y158195D01*
Y157888D01*
X540395Y157543D01*
X540137Y157275D01*
X539827Y157083D01*
X539310Y156930D01*
X538845Y156892D01*
X538380Y156968D01*
X538070Y157083D01*
X537760Y157313D01*
X537553Y157582D01*
X537450Y157850D01*
Y158118D01*
X537553Y158387D01*
X537708Y158617D01*
X537915Y158808D01*
G01X537450Y160950D02*
X540550D01*
X539930Y160490D01*
G01X537450D02*
Y161410D01*
G01Y163973D02*
X538122Y164050D01*
X538690Y164165D01*
X539207Y164318D01*
X539775Y164510D01*
X540550Y164817D01*
Y163283D01*
G01X537450Y167150D02*
X537502Y167418D01*
X537657Y167725D01*
X537915Y167917D01*
X538277Y167993D01*
X538638Y167917D01*
X538948Y167687D01*
X539103Y167342D01*
Y166958D01*
X539207Y166728D01*
X539465Y166537D01*
X539827Y166460D01*
X540188Y166575D01*
X540447Y166843D01*
X540550Y167150D01*
X540447Y167457D01*
X540188Y167725D01*
X539827Y167840D01*
X539465Y167763D01*
X539207Y167572D01*
X539103Y167342D01*
Y166958D01*
X538948Y166613D01*
X538638Y166383D01*
X538277Y166307D01*
X537915Y166383D01*
X537657Y166575D01*
X537502Y166882D01*
X537450Y167150D01*
G01X541842Y178693D02*
X541997Y178463D01*
X542100Y178195D01*
Y177888D01*
X541945Y177543D01*
X541687Y177275D01*
X541377Y177083D01*
X540860Y176930D01*
X540395Y176892D01*
X539930Y176968D01*
X539620Y177083D01*
X539310Y177313D01*
X539103Y177582D01*
X539000Y177850D01*
Y178118D01*
X539103Y178387D01*
X539258Y178617D01*
X539465Y178808D01*
G01X539000Y180950D02*
X542100D01*
X541480Y180490D01*
G01X539000D02*
Y181410D01*
G01Y183973D02*
X539672Y184050D01*
X540240Y184165D01*
X540757Y184318D01*
X541325Y184510D01*
X542100Y184817D01*
Y183283D01*
G01X539362Y186498D02*
X539103Y186767D01*
X539000Y187073D01*
X539103Y187380D01*
X539413Y187648D01*
X539878Y187840D01*
X540343Y187917D01*
X540912D01*
X541377Y187840D01*
X541790Y187648D01*
X541997Y187418D01*
X542100Y187150D01*
X541997Y186843D01*
X541790Y186613D01*
X541480Y186460D01*
X541067Y186383D01*
X540705Y186460D01*
X540343Y186652D01*
X540137Y186882D01*
X540085Y187150D01*
X540188Y187457D01*
X540447Y187687D01*
X540912Y187917D01*
G01X552342Y198193D02*
X552497Y197963D01*
X552600Y197695D01*
Y197388D01*
X552445Y197043D01*
X552187Y196775D01*
X551877Y196583D01*
X551360Y196430D01*
X550895Y196392D01*
X550430Y196468D01*
X550120Y196583D01*
X549810Y196813D01*
X549603Y197082D01*
X549500Y197350D01*
Y197618D01*
X549603Y197887D01*
X549758Y198117D01*
X549965Y198308D01*
G01X552083Y199722D02*
X552393Y199952D01*
X552548Y200220D01*
X552600Y200527D01*
X552497Y200910D01*
X552238Y201178D01*
X551928Y201255D01*
X551618Y201217D01*
X551360Y201063D01*
X550843Y200297D01*
X550482Y199952D01*
X549965Y199722D01*
X549500Y199645D01*
Y201255D01*
G01X550792Y202822D02*
X551153Y203090D01*
X551360Y203320D01*
X551463Y203627D01*
X551360Y203895D01*
X551153Y204087D01*
X550843Y204240D01*
X550482Y204278D01*
X550172Y204240D01*
X549862Y204087D01*
X549603Y203857D01*
X549500Y203588D01*
X549603Y203282D01*
X549913Y203013D01*
X550378Y202860D01*
X550895Y202822D01*
X551567Y202898D01*
X551928Y203013D01*
X552290Y203205D01*
X552548Y203473D01*
X552600Y203742D01*
X552497Y204010D01*
X552238Y204202D01*
G01X549965Y205807D02*
X549707Y206037D01*
X549552Y206305D01*
X549500Y206650D01*
X549603Y206995D01*
X549810Y207263D01*
X550172Y207455D01*
X550585Y207493D01*
X550998Y207417D01*
X551257Y207225D01*
X551463Y206957D01*
X551515Y206688D01*
X551463Y206420D01*
X551257Y206075D01*
X552600Y206190D01*
Y207225D01*
G01X549966Y209583D02*
X553066D01*
Y210542D01*
X552911Y210848D01*
X552704Y211040D01*
X552291Y211117D01*
X551878Y211040D01*
X551619Y210810D01*
X551464Y210542D01*
Y209583D01*
G01Y210542D02*
X549966Y211117D01*
G01X552549Y212722D02*
X552859Y212952D01*
X553014Y213220D01*
X553066Y213527D01*
X552963Y213910D01*
X552704Y214178D01*
X552394Y214255D01*
X552084Y214217D01*
X551826Y214063D01*
X551309Y213297D01*
X550948Y212952D01*
X550431Y212722D01*
X549966Y212645D01*
Y214255D01*
G01X550431Y215707D02*
X550173Y215937D01*
X550018Y216205D01*
X549966Y216550D01*
X550069Y216895D01*
X550276Y217163D01*
X550638Y217355D01*
X551051Y217393D01*
X551464Y217317D01*
X551723Y217125D01*
X551929Y216857D01*
X551981Y216588D01*
X551929Y216320D01*
X551723Y215975D01*
X553066Y216090D01*
Y217125D01*
G01Y219650D02*
X552963Y219343D01*
X552704Y219113D01*
X552394Y218960D01*
X551981Y218845D01*
X551516Y218807D01*
X551051Y218845D01*
X550638Y218960D01*
X550328Y219113D01*
X550069Y219343D01*
X549966Y219650D01*
X550069Y219957D01*
X550328Y220187D01*
X550638Y220340D01*
X551051Y220455D01*
X551516Y220493D01*
X551981Y220455D01*
X552394Y220340D01*
X552704Y220187D01*
X552963Y219957D01*
X553066Y219650D01*
G01X549450Y229083D02*
X552550D01*
Y230042D01*
X552395Y230348D01*
X552188Y230540D01*
X551775Y230617D01*
X551362Y230540D01*
X551103Y230310D01*
X550948Y230042D01*
Y229083D01*
G01Y230042D02*
X549450Y230617D01*
G01X552033Y232222D02*
X552343Y232452D01*
X552498Y232720D01*
X552550Y233027D01*
X552447Y233410D01*
X552188Y233678D01*
X551878Y233755D01*
X551568Y233717D01*
X551310Y233563D01*
X550793Y232797D01*
X550432Y232452D01*
X549915Y232222D01*
X549450Y232145D01*
Y233755D01*
G01Y236510D02*
X552550D01*
X550328Y235092D01*
Y237008D01*
G01X549450Y239610D02*
X552550D01*
X550328Y238192D01*
Y240108D01*
G01X545466Y229083D02*
X548566D01*
Y230042D01*
X548411Y230348D01*
X548204Y230540D01*
X547791Y230617D01*
X547378Y230540D01*
X547119Y230310D01*
X546964Y230042D01*
Y229083D01*
G01Y230042D02*
X545466Y230617D01*
G01X548049Y232222D02*
X548359Y232452D01*
X548514Y232720D01*
X548566Y233027D01*
X548463Y233410D01*
X548204Y233678D01*
X547894Y233755D01*
X547584Y233717D01*
X547326Y233563D01*
X546809Y232797D01*
X546448Y232452D01*
X545931Y232222D01*
X545466Y232145D01*
Y233755D01*
G01Y236510D02*
X548566D01*
X546344Y235092D01*
Y237008D01*
G01X545466Y239073D02*
X546138Y239150D01*
X546706Y239265D01*
X547223Y239418D01*
X547791Y239610D01*
X548566Y239917D01*
Y238383D01*
G01X543950Y259083D02*
X547050D01*
Y260042D01*
X546895Y260348D01*
X546688Y260540D01*
X546275Y260617D01*
X545862Y260540D01*
X545603Y260310D01*
X545448Y260042D01*
Y259083D01*
G01Y260042D02*
X543950Y260617D01*
G01Y263410D02*
X547050D01*
X544828Y261992D01*
Y263908D01*
G01X547050Y266050D02*
X546947Y265743D01*
X546688Y265513D01*
X546378Y265360D01*
X545965Y265245D01*
X545500Y265207D01*
X545035Y265245D01*
X544622Y265360D01*
X544312Y265513D01*
X544053Y265743D01*
X543950Y266050D01*
X544053Y266357D01*
X544312Y266587D01*
X544622Y266740D01*
X545035Y266855D01*
X545500Y266893D01*
X545965Y266855D01*
X546378Y266740D01*
X546688Y266587D01*
X546947Y266357D01*
X547050Y266050D01*
G01X546533Y268422D02*
X546843Y268652D01*
X546998Y268920D01*
X547050Y269227D01*
X546947Y269610D01*
X546688Y269878D01*
X546378Y269955D01*
X546068Y269917D01*
X545810Y269763D01*
X545293Y268997D01*
X544932Y268652D01*
X544415Y268422D01*
X543950Y268345D01*
Y269955D01*
G01X560617Y262750D02*
Y265850D01*
X559658D01*
X559352Y265695D01*
X559160Y265488D01*
X559083Y265075D01*
X559160Y264662D01*
X559390Y264403D01*
X559658Y264248D01*
X560617D01*
G01X559658D02*
X559083Y262750D01*
G01X556750D02*
Y265850D01*
X557210Y265230D01*
G01Y262750D02*
X556290D01*
G01X554493Y263370D02*
X554263Y263008D01*
X553957Y262802D01*
X553612Y262750D01*
X553305Y262802D01*
X552998Y263060D01*
X552807Y263370D01*
X552768Y263680D01*
X552845Y264042D01*
X553113Y264300D01*
X553382Y264403D01*
X553727D01*
G01X553382D02*
X553152Y264558D01*
X552960Y264817D01*
X552883Y265127D01*
X552960Y265437D01*
X553152Y265695D01*
X553497Y265850D01*
X553842Y265798D01*
X554187Y265592D01*
G01X550090Y262750D02*
Y265850D01*
X551508Y263628D01*
X549592D01*
G01X556367Y257950D02*
Y261050D01*
X555408D01*
X555102Y260895D01*
X554910Y260688D01*
X554833Y260275D01*
X554910Y259862D01*
X555140Y259603D01*
X555408Y259448D01*
X556367D01*
G01X555408D02*
X554833Y257950D01*
G01X553228Y260533D02*
X552998Y260843D01*
X552730Y260998D01*
X552423Y261050D01*
X552040Y260947D01*
X551772Y260688D01*
X551695Y260378D01*
X551733Y260068D01*
X551887Y259810D01*
X552653Y259293D01*
X552998Y258932D01*
X553228Y258415D01*
X553305Y257950D01*
X551695D01*
G01X549400D02*
X549132Y258002D01*
X548825Y258157D01*
X548633Y258415D01*
X548557Y258777D01*
X548633Y259138D01*
X548863Y259448D01*
X549208Y259603D01*
X549592D01*
X549822Y259707D01*
X550013Y259965D01*
X550090Y260327D01*
X549975Y260688D01*
X549707Y260947D01*
X549400Y261050D01*
X549093Y260947D01*
X548825Y260688D01*
X548710Y260327D01*
X548787Y259965D01*
X548978Y259707D01*
X549208Y259603D01*
X549592D01*
X549937Y259448D01*
X550167Y259138D01*
X550243Y258777D01*
X550167Y258415D01*
X549975Y258157D01*
X549668Y258002D01*
X549400Y257950D01*
G01X543950Y272083D02*
X547050D01*
Y273042D01*
X546895Y273348D01*
X546688Y273540D01*
X546275Y273617D01*
X545862Y273540D01*
X545603Y273310D01*
X545448Y273042D01*
Y272083D01*
G01Y273042D02*
X543950Y273617D01*
G01Y276410D02*
X547050D01*
X544828Y274992D01*
Y276908D01*
G01X547050Y279050D02*
X546947Y278743D01*
X546688Y278513D01*
X546378Y278360D01*
X545965Y278245D01*
X545500Y278207D01*
X545035Y278245D01*
X544622Y278360D01*
X544312Y278513D01*
X544053Y278743D01*
X543950Y279050D01*
X544053Y279357D01*
X544312Y279587D01*
X544622Y279740D01*
X545035Y279855D01*
X545500Y279893D01*
X545965Y279855D01*
X546378Y279740D01*
X546688Y279587D01*
X546947Y279357D01*
X547050Y279050D01*
G01X544570Y281307D02*
X544208Y281537D01*
X544002Y281843D01*
X543950Y282188D01*
X544002Y282495D01*
X544260Y282802D01*
X544570Y282993D01*
X544880Y283032D01*
X545242Y282955D01*
X545500Y282687D01*
X545603Y282418D01*
Y282073D01*
G01Y282418D02*
X545758Y282648D01*
X546017Y282840D01*
X546327Y282917D01*
X546637Y282840D01*
X546895Y282648D01*
X547050Y282303D01*
X546998Y281958D01*
X546792Y281613D01*
G01X559717Y270550D02*
Y273650D01*
X558758D01*
X558452Y273495D01*
X558260Y273288D01*
X558183Y272875D01*
X558260Y272462D01*
X558490Y272203D01*
X558758Y272048D01*
X559717D01*
G01X558758D02*
X558183Y270550D01*
G01X555850D02*
Y273650D01*
X556310Y273030D01*
G01Y270550D02*
X555390D01*
G01X553593Y271170D02*
X553363Y270808D01*
X553057Y270602D01*
X552712Y270550D01*
X552405Y270602D01*
X552098Y270860D01*
X551907Y271170D01*
X551868Y271480D01*
X551945Y271842D01*
X552213Y272100D01*
X552482Y272203D01*
X552827D01*
G01X552482D02*
X552252Y272358D01*
X552060Y272617D01*
X551983Y272927D01*
X552060Y273237D01*
X552252Y273495D01*
X552597Y273650D01*
X552942Y273598D01*
X553287Y273392D01*
G01X550493Y271170D02*
X550263Y270808D01*
X549957Y270602D01*
X549612Y270550D01*
X549305Y270602D01*
X548998Y270860D01*
X548807Y271170D01*
X548768Y271480D01*
X548845Y271842D01*
X549113Y272100D01*
X549382Y272203D01*
X549727D01*
G01X549382D02*
X549152Y272358D01*
X548960Y272617D01*
X548883Y272927D01*
X548960Y273237D01*
X549152Y273495D01*
X549497Y273650D01*
X549842Y273598D01*
X550187Y273392D01*
G01X559917Y275450D02*
Y278550D01*
X558958D01*
X558652Y278395D01*
X558460Y278188D01*
X558383Y277775D01*
X558460Y277362D01*
X558690Y277103D01*
X558958Y276948D01*
X559917D01*
G01X558958D02*
X558383Y275450D01*
G01X556050D02*
Y278550D01*
X556510Y277930D01*
G01Y275450D02*
X555590D01*
G01X553793Y276070D02*
X553563Y275708D01*
X553257Y275502D01*
X552912Y275450D01*
X552605Y275502D01*
X552298Y275760D01*
X552107Y276070D01*
X552068Y276380D01*
X552145Y276742D01*
X552413Y277000D01*
X552682Y277103D01*
X553027D01*
G01X552682D02*
X552452Y277258D01*
X552260Y277517D01*
X552183Y277827D01*
X552260Y278137D01*
X552452Y278395D01*
X552797Y278550D01*
X553142Y278498D01*
X553487Y278292D01*
G01X550693Y275915D02*
X550463Y275657D01*
X550195Y275502D01*
X549850Y275450D01*
X549505Y275553D01*
X549237Y275760D01*
X549045Y276122D01*
X549007Y276535D01*
X549083Y276948D01*
X549275Y277207D01*
X549543Y277413D01*
X549812Y277465D01*
X550080Y277413D01*
X550425Y277207D01*
X550310Y278550D01*
X549275D01*
G01X556367Y279950D02*
Y283050D01*
X555408D01*
X555102Y282895D01*
X554910Y282688D01*
X554833Y282275D01*
X554910Y281862D01*
X555140Y281603D01*
X555408Y281448D01*
X556367D01*
G01X555408D02*
X554833Y279950D01*
G01X552040D02*
Y283050D01*
X553458Y280828D01*
X551542D01*
G01X550128Y282533D02*
X549898Y282843D01*
X549630Y282998D01*
X549323Y283050D01*
X548940Y282947D01*
X548672Y282688D01*
X548595Y282378D01*
X548633Y282068D01*
X548787Y281810D01*
X549553Y281293D01*
X549898Y280932D01*
X550128Y280415D01*
X550205Y279950D01*
X548595D01*
G01X550867Y285450D02*
Y288550D01*
X549908D01*
X549602Y288395D01*
X549410Y288188D01*
X549333Y287775D01*
X549410Y287362D01*
X549640Y287103D01*
X549908Y286948D01*
X550867D01*
G01X549908D02*
X549333Y285450D01*
G01X546540D02*
Y288550D01*
X547958Y286328D01*
X546042D01*
G01X544743Y286070D02*
X544513Y285708D01*
X544207Y285502D01*
X543862Y285450D01*
X543555Y285502D01*
X543248Y285760D01*
X543057Y286070D01*
X543018Y286380D01*
X543095Y286742D01*
X543363Y287000D01*
X543632Y287103D01*
X543977D01*
G01X543632D02*
X543402Y287258D01*
X543210Y287517D01*
X543133Y287827D01*
X543210Y288137D01*
X543402Y288395D01*
X543747Y288550D01*
X544092Y288498D01*
X544437Y288292D01*
G01X543450Y290083D02*
X546550D01*
Y291042D01*
X546395Y291348D01*
X546188Y291540D01*
X545775Y291617D01*
X545362Y291540D01*
X545103Y291310D01*
X544948Y291042D01*
Y290083D01*
G01Y291042D02*
X543450Y291617D01*
G01Y294410D02*
X546550D01*
X544328Y292992D01*
Y294908D01*
G01X546550Y297050D02*
X546447Y296743D01*
X546188Y296513D01*
X545878Y296360D01*
X545465Y296245D01*
X545000Y296207D01*
X544535Y296245D01*
X544122Y296360D01*
X543812Y296513D01*
X543553Y296743D01*
X543450Y297050D01*
X543553Y297357D01*
X543812Y297587D01*
X544122Y297740D01*
X544535Y297855D01*
X545000Y297893D01*
X545465Y297855D01*
X545878Y297740D01*
X546188Y297587D01*
X546447Y297357D01*
X546550Y297050D01*
G01X543450Y300610D02*
X546550D01*
X544328Y299192D01*
Y301108D01*
G01X543450Y302083D02*
X546550D01*
Y303042D01*
X546395Y303348D01*
X546188Y303540D01*
X545775Y303617D01*
X545362Y303540D01*
X545103Y303310D01*
X544948Y303042D01*
Y302083D01*
G01Y303042D02*
X543450Y303617D01*
G01Y306410D02*
X546550D01*
X544328Y304992D01*
Y306908D01*
G01X546550Y309050D02*
X546447Y308743D01*
X546188Y308513D01*
X545878Y308360D01*
X545465Y308245D01*
X545000Y308207D01*
X544535Y308245D01*
X544122Y308360D01*
X543812Y308513D01*
X543553Y308743D01*
X543450Y309050D01*
X543553Y309357D01*
X543812Y309587D01*
X544122Y309740D01*
X544535Y309855D01*
X545000Y309893D01*
X545465Y309855D01*
X545878Y309740D01*
X546188Y309587D01*
X546447Y309357D01*
X546550Y309050D01*
G01X543915Y311307D02*
X543657Y311537D01*
X543502Y311805D01*
X543450Y312150D01*
X543553Y312495D01*
X543760Y312763D01*
X544122Y312955D01*
X544535Y312993D01*
X544948Y312917D01*
X545207Y312725D01*
X545413Y312457D01*
X545465Y312188D01*
X545413Y311920D01*
X545207Y311575D01*
X546550Y311690D01*
Y312725D01*
G01X560417Y290500D02*
Y293600D01*
X559458D01*
X559152Y293445D01*
X558960Y293238D01*
X558883Y292825D01*
X558960Y292412D01*
X559190Y292153D01*
X559458Y291998D01*
X560417D01*
G01X559458D02*
X558883Y290500D01*
G01X556550D02*
Y293600D01*
X557010Y292980D01*
G01Y290500D02*
X556090D01*
G01X554293Y291120D02*
X554063Y290758D01*
X553757Y290552D01*
X553412Y290500D01*
X553105Y290552D01*
X552798Y290810D01*
X552607Y291120D01*
X552568Y291430D01*
X552645Y291792D01*
X552913Y292050D01*
X553182Y292153D01*
X553527D01*
G01X553182D02*
X552952Y292308D01*
X552760Y292567D01*
X552683Y292877D01*
X552760Y293187D01*
X552952Y293445D01*
X553297Y293600D01*
X553642Y293548D01*
X553987Y293342D01*
G01X551078Y291792D02*
X550810Y292153D01*
X550580Y292360D01*
X550273Y292463D01*
X550005Y292360D01*
X549813Y292153D01*
X549660Y291843D01*
X549622Y291482D01*
X549660Y291172D01*
X549813Y290862D01*
X550043Y290603D01*
X550312Y290500D01*
X550618Y290603D01*
X550887Y290913D01*
X551040Y291378D01*
X551078Y291895D01*
X551002Y292567D01*
X550887Y292928D01*
X550695Y293290D01*
X550427Y293548D01*
X550158Y293600D01*
X549890Y293497D01*
X549698Y293238D01*
G01X560117Y300600D02*
Y303700D01*
X559158D01*
X558852Y303545D01*
X558660Y303338D01*
X558583Y302925D01*
X558660Y302512D01*
X558890Y302253D01*
X559158Y302098D01*
X560117D01*
G01X559158D02*
X558583Y300600D01*
G01X556250D02*
Y303700D01*
X556710Y303080D01*
G01Y300600D02*
X555790D01*
G01X553993Y301220D02*
X553763Y300858D01*
X553457Y300652D01*
X553112Y300600D01*
X552805Y300652D01*
X552498Y300910D01*
X552307Y301220D01*
X552268Y301530D01*
X552345Y301892D01*
X552613Y302150D01*
X552882Y302253D01*
X553227D01*
G01X552882D02*
X552652Y302408D01*
X552460Y302667D01*
X552383Y302977D01*
X552460Y303287D01*
X552652Y303545D01*
X552997Y303700D01*
X553342Y303648D01*
X553687Y303442D01*
G01X550127Y300600D02*
X550050Y301272D01*
X549935Y301840D01*
X549782Y302357D01*
X549590Y302925D01*
X549283Y303700D01*
X550817D01*
G01X553207Y322924D02*
X553437Y323079D01*
X553705Y323182D01*
X554012D01*
X554357Y323027D01*
X554625Y322769D01*
X554817Y322459D01*
X554970Y321942D01*
X555008Y321477D01*
X554932Y321012D01*
X554817Y320702D01*
X554587Y320392D01*
X554318Y320185D01*
X554050Y320082D01*
X553782D01*
X553513Y320185D01*
X553283Y320340D01*
X553092Y320547D01*
G01X551793Y320702D02*
X551563Y320340D01*
X551257Y320134D01*
X550912Y320082D01*
X550605Y320134D01*
X550298Y320392D01*
X550107Y320702D01*
X550068Y321012D01*
X550145Y321374D01*
X550413Y321632D01*
X550682Y321735D01*
X551027D01*
G01X550682D02*
X550452Y321890D01*
X550260Y322149D01*
X550183Y322459D01*
X550260Y322769D01*
X550452Y323027D01*
X550797Y323182D01*
X551142Y323130D01*
X551487Y322924D01*
G01X547850Y323182D02*
X548157Y323079D01*
X548387Y322820D01*
X548540Y322510D01*
X548655Y322097D01*
X548693Y321632D01*
X548655Y321167D01*
X548540Y320754D01*
X548387Y320444D01*
X548157Y320185D01*
X547850Y320082D01*
X547543Y320185D01*
X547313Y320444D01*
X547160Y320754D01*
X547045Y321167D01*
X547007Y321632D01*
X547045Y322097D01*
X547160Y322510D01*
X547313Y322820D01*
X547543Y323079D01*
X547850Y323182D01*
G01X545593Y320702D02*
X545363Y320340D01*
X545057Y320134D01*
X544712Y320082D01*
X544405Y320134D01*
X544098Y320392D01*
X543907Y320702D01*
X543868Y321012D01*
X543945Y321374D01*
X544213Y321632D01*
X544482Y321735D01*
X544827D01*
G01X544482D02*
X544252Y321890D01*
X544060Y322149D01*
X543983Y322459D01*
X544060Y322769D01*
X544252Y323027D01*
X544597Y323182D01*
X544942Y323130D01*
X545287Y322924D01*
G01X556367Y304950D02*
Y308050D01*
X555408D01*
X555102Y307895D01*
X554910Y307688D01*
X554833Y307275D01*
X554910Y306862D01*
X555140Y306603D01*
X555408Y306448D01*
X556367D01*
G01X555408D02*
X554833Y304950D01*
G01X552040D02*
Y308050D01*
X553458Y305828D01*
X551542D01*
G01X549400Y304950D02*
Y308050D01*
X549860Y307430D01*
G01Y304950D02*
X548940D01*
G01X553607Y338724D02*
X553837Y338879D01*
X554105Y338982D01*
X554412D01*
X554757Y338827D01*
X555025Y338569D01*
X555217Y338259D01*
X555370Y337742D01*
X555408Y337277D01*
X555332Y336812D01*
X555217Y336502D01*
X554987Y336192D01*
X554718Y335985D01*
X554450Y335882D01*
X554182D01*
X553913Y335985D01*
X553683Y336140D01*
X553492Y336347D01*
G01X552078Y338465D02*
X551848Y338775D01*
X551580Y338930D01*
X551273Y338982D01*
X550890Y338879D01*
X550622Y338620D01*
X550545Y338310D01*
X550583Y338000D01*
X550737Y337742D01*
X551503Y337225D01*
X551848Y336864D01*
X552078Y336347D01*
X552155Y335882D01*
X550545D01*
G01X548902Y336244D02*
X548633Y335985D01*
X548327Y335882D01*
X548020Y335985D01*
X547752Y336295D01*
X547560Y336760D01*
X547483Y337225D01*
Y337794D01*
X547560Y338259D01*
X547752Y338672D01*
X547982Y338879D01*
X548250Y338982D01*
X548557Y338879D01*
X548787Y338672D01*
X548940Y338362D01*
X549017Y337949D01*
X548940Y337587D01*
X548748Y337225D01*
X548518Y337019D01*
X548250Y336967D01*
X547943Y337070D01*
X547713Y337329D01*
X547483Y337794D01*
G01X545227Y335882D02*
X545150Y336554D01*
X545035Y337122D01*
X544882Y337639D01*
X544690Y338207D01*
X544383Y338982D01*
X545917D01*
G01X553607Y331124D02*
X553837Y331279D01*
X554105Y331382D01*
X554412D01*
X554757Y331227D01*
X555025Y330969D01*
X555217Y330659D01*
X555370Y330142D01*
X555408Y329677D01*
X555332Y329212D01*
X555217Y328902D01*
X554987Y328592D01*
X554718Y328385D01*
X554450Y328282D01*
X554182D01*
X553913Y328385D01*
X553683Y328540D01*
X553492Y328747D01*
G01X552078Y330865D02*
X551848Y331175D01*
X551580Y331330D01*
X551273Y331382D01*
X550890Y331279D01*
X550622Y331020D01*
X550545Y330710D01*
X550583Y330400D01*
X550737Y330142D01*
X551503Y329625D01*
X551848Y329264D01*
X552078Y328747D01*
X552155Y328282D01*
X550545D01*
G01X548902Y328644D02*
X548633Y328385D01*
X548327Y328282D01*
X548020Y328385D01*
X547752Y328695D01*
X547560Y329160D01*
X547483Y329625D01*
Y330194D01*
X547560Y330659D01*
X547752Y331072D01*
X547982Y331279D01*
X548250Y331382D01*
X548557Y331279D01*
X548787Y331072D01*
X548940Y330762D01*
X549017Y330349D01*
X548940Y329987D01*
X548748Y329625D01*
X548518Y329419D01*
X548250Y329367D01*
X547943Y329470D01*
X547713Y329729D01*
X547483Y330194D01*
G01X545802Y328644D02*
X545533Y328385D01*
X545227Y328282D01*
X544920Y328385D01*
X544652Y328695D01*
X544460Y329160D01*
X544383Y329625D01*
Y330194D01*
X544460Y330659D01*
X544652Y331072D01*
X544882Y331279D01*
X545150Y331382D01*
X545457Y331279D01*
X545687Y331072D01*
X545840Y330762D01*
X545917Y330349D01*
X545840Y329987D01*
X545648Y329625D01*
X545418Y329419D01*
X545150Y329367D01*
X544843Y329470D01*
X544613Y329729D01*
X544383Y330194D01*
G01X553607Y346424D02*
X553837Y346579D01*
X554105Y346682D01*
X554412D01*
X554757Y346527D01*
X555025Y346269D01*
X555217Y345959D01*
X555370Y345442D01*
X555408Y344977D01*
X555332Y344512D01*
X555217Y344202D01*
X554987Y343892D01*
X554718Y343685D01*
X554450Y343582D01*
X554182D01*
X553913Y343685D01*
X553683Y343840D01*
X553492Y344047D01*
G01X552193Y344202D02*
X551963Y343840D01*
X551657Y343634D01*
X551312Y343582D01*
X551005Y343634D01*
X550698Y343892D01*
X550507Y344202D01*
X550468Y344512D01*
X550545Y344874D01*
X550813Y345132D01*
X551082Y345235D01*
X551427D01*
G01X551082D02*
X550852Y345390D01*
X550660Y345649D01*
X550583Y345959D01*
X550660Y346269D01*
X550852Y346527D01*
X551197Y346682D01*
X551542Y346630D01*
X551887Y346424D01*
G01X548250Y346682D02*
X548557Y346579D01*
X548787Y346320D01*
X548940Y346010D01*
X549055Y345597D01*
X549093Y345132D01*
X549055Y344667D01*
X548940Y344254D01*
X548787Y343944D01*
X548557Y343685D01*
X548250Y343582D01*
X547943Y343685D01*
X547713Y343944D01*
X547560Y344254D01*
X547445Y344667D01*
X547407Y345132D01*
X547445Y345597D01*
X547560Y346010D01*
X547713Y346320D01*
X547943Y346579D01*
X548250Y346682D01*
G01X545150Y343582D02*
Y346682D01*
X545610Y346062D01*
G01Y343582D02*
X544690D01*
G01X541450Y407583D02*
X544550D01*
Y408542D01*
X544395Y408848D01*
X544188Y409040D01*
X543775Y409117D01*
X543362Y409040D01*
X543103Y408810D01*
X542948Y408542D01*
Y407583D01*
G01Y408542D02*
X541450Y409117D01*
G01Y411450D02*
X544550D01*
X543930Y410990D01*
G01X541450D02*
Y411910D01*
G01X542070Y413707D02*
X541708Y413937D01*
X541502Y414243D01*
X541450Y414588D01*
X541502Y414895D01*
X541760Y415202D01*
X542070Y415393D01*
X542380Y415432D01*
X542742Y415355D01*
X543000Y415087D01*
X543103Y414818D01*
Y414473D01*
G01Y414818D02*
X543258Y415048D01*
X543517Y415240D01*
X543827Y415317D01*
X544137Y415240D01*
X544395Y415048D01*
X544550Y414703D01*
X544498Y414358D01*
X544292Y414013D01*
G01X541450Y417650D02*
X541502Y417918D01*
X541657Y418225D01*
X541915Y418417D01*
X542277Y418493D01*
X542638Y418417D01*
X542948Y418187D01*
X543103Y417842D01*
Y417458D01*
X543207Y417228D01*
X543465Y417037D01*
X543827Y416960D01*
X544188Y417075D01*
X544447Y417343D01*
X544550Y417650D01*
X544447Y417957D01*
X544188Y418225D01*
X543827Y418340D01*
X543465Y418263D01*
X543207Y418072D01*
X543103Y417842D01*
Y417458D01*
X542948Y417113D01*
X542638Y416883D01*
X542277Y416807D01*
X541915Y416883D01*
X541657Y417075D01*
X541502Y417382D01*
X541450Y417650D01*
G01X560417Y405450D02*
Y408550D01*
X559458D01*
X559152Y408395D01*
X558960Y408188D01*
X558883Y407775D01*
X558960Y407362D01*
X559190Y407103D01*
X559458Y406948D01*
X560417D01*
G01X559458D02*
X558883Y405450D01*
G01X556550D02*
Y408550D01*
X557010Y407930D01*
G01Y405450D02*
X556090D01*
G01X554293Y406070D02*
X554063Y405708D01*
X553757Y405502D01*
X553412Y405450D01*
X553105Y405502D01*
X552798Y405760D01*
X552607Y406070D01*
X552568Y406380D01*
X552645Y406742D01*
X552913Y407000D01*
X553182Y407103D01*
X553527D01*
G01X553182D02*
X552952Y407258D01*
X552760Y407517D01*
X552683Y407827D01*
X552760Y408137D01*
X552952Y408395D01*
X553297Y408550D01*
X553642Y408498D01*
X553987Y408292D01*
G01X551002Y405812D02*
X550733Y405553D01*
X550427Y405450D01*
X550120Y405553D01*
X549852Y405863D01*
X549660Y406328D01*
X549583Y406793D01*
Y407362D01*
X549660Y407827D01*
X549852Y408240D01*
X550082Y408447D01*
X550350Y408550D01*
X550657Y408447D01*
X550887Y408240D01*
X551040Y407930D01*
X551117Y407517D01*
X551040Y407155D01*
X550848Y406793D01*
X550618Y406587D01*
X550350Y406535D01*
X550043Y406638D01*
X549813Y406897D01*
X549583Y407362D01*
G01X560417Y409950D02*
Y413050D01*
X559458D01*
X559152Y412895D01*
X558960Y412688D01*
X558883Y412275D01*
X558960Y411862D01*
X559190Y411603D01*
X559458Y411448D01*
X560417D01*
G01X559458D02*
X558883Y409950D01*
G01X556550D02*
Y413050D01*
X557010Y412430D01*
G01Y409950D02*
X556090D01*
G01X553450Y413050D02*
X553757Y412947D01*
X553987Y412688D01*
X554140Y412378D01*
X554255Y411965D01*
X554293Y411500D01*
X554255Y411035D01*
X554140Y410622D01*
X553987Y410312D01*
X553757Y410053D01*
X553450Y409950D01*
X553143Y410053D01*
X552913Y410312D01*
X552760Y410622D01*
X552645Y411035D01*
X552607Y411500D01*
X552645Y411965D01*
X552760Y412378D01*
X552913Y412688D01*
X553143Y412947D01*
X553450Y413050D01*
G01X550350Y409950D02*
X550082Y410002D01*
X549775Y410157D01*
X549583Y410415D01*
X549507Y410777D01*
X549583Y411138D01*
X549813Y411448D01*
X550158Y411603D01*
X550542D01*
X550772Y411707D01*
X550963Y411965D01*
X551040Y412327D01*
X550925Y412688D01*
X550657Y412947D01*
X550350Y413050D01*
X550043Y412947D01*
X549775Y412688D01*
X549660Y412327D01*
X549737Y411965D01*
X549928Y411707D01*
X550158Y411603D01*
X550542D01*
X550887Y411448D01*
X551117Y411138D01*
X551193Y410777D01*
X551117Y410415D01*
X550925Y410157D01*
X550618Y410002D01*
X550350Y409950D01*
G01X541450Y420583D02*
X544550D01*
Y421542D01*
X544395Y421848D01*
X544188Y422040D01*
X543775Y422117D01*
X543362Y422040D01*
X543103Y421810D01*
X542948Y421542D01*
Y420583D01*
G01Y421542D02*
X541450Y422117D01*
G01X544033Y423722D02*
X544343Y423952D01*
X544498Y424220D01*
X544550Y424527D01*
X544447Y424910D01*
X544188Y425178D01*
X543878Y425255D01*
X543568Y425217D01*
X543310Y425063D01*
X542793Y424297D01*
X542432Y423952D01*
X541915Y423722D01*
X541450Y423645D01*
Y425255D01*
G01X541915Y426707D02*
X541657Y426937D01*
X541502Y427205D01*
X541450Y427550D01*
X541553Y427895D01*
X541760Y428163D01*
X542122Y428355D01*
X542535Y428393D01*
X542948Y428317D01*
X543207Y428125D01*
X543413Y427857D01*
X543465Y427588D01*
X543413Y427320D01*
X543207Y426975D01*
X544550Y427090D01*
Y428125D01*
G01X541450Y430573D02*
X542122Y430650D01*
X542690Y430765D01*
X543207Y430918D01*
X543775Y431110D01*
X544550Y431417D01*
Y429883D01*
G01X553950Y57483D02*
X557050D01*
Y58442D01*
X556895Y58748D01*
X556688Y58940D01*
X556275Y59017D01*
X555862Y58940D01*
X555603Y58710D01*
X555448Y58442D01*
Y57483D01*
G01Y58442D02*
X553950Y59017D01*
G01X556533Y60622D02*
X556843Y60852D01*
X556998Y61120D01*
X557050Y61427D01*
X556947Y61810D01*
X556688Y62078D01*
X556378Y62155D01*
X556068Y62117D01*
X555810Y61963D01*
X555293Y61197D01*
X554932Y60852D01*
X554415Y60622D01*
X553950Y60545D01*
Y62155D01*
G01X556533Y63722D02*
X556843Y63952D01*
X556998Y64220D01*
X557050Y64527D01*
X556947Y64910D01*
X556688Y65178D01*
X556378Y65255D01*
X556068Y65217D01*
X555810Y65063D01*
X555293Y64297D01*
X554932Y63952D01*
X554415Y63722D01*
X553950Y63645D01*
Y65255D01*
G01X554312Y66898D02*
X554053Y67167D01*
X553950Y67473D01*
X554053Y67780D01*
X554363Y68048D01*
X554828Y68240D01*
X555293Y68317D01*
X555862D01*
X556327Y68240D01*
X556740Y68048D01*
X556947Y67818D01*
X557050Y67550D01*
X556947Y67243D01*
X556740Y67013D01*
X556430Y66860D01*
X556017Y66783D01*
X555655Y66860D01*
X555293Y67052D01*
X555087Y67282D01*
X555035Y67550D01*
X555138Y67857D01*
X555397Y68087D01*
X555862Y68317D01*
G01X553500Y70583D02*
X556600D01*
Y71542D01*
X556445Y71848D01*
X556238Y72040D01*
X555825Y72117D01*
X555412Y72040D01*
X555153Y71810D01*
X554998Y71542D01*
Y70583D01*
G01Y71542D02*
X553500Y72117D01*
G01X556083Y73722D02*
X556393Y73952D01*
X556548Y74220D01*
X556600Y74527D01*
X556497Y74910D01*
X556238Y75178D01*
X555928Y75255D01*
X555618Y75217D01*
X555360Y75063D01*
X554843Y74297D01*
X554482Y73952D01*
X553965Y73722D01*
X553500Y73645D01*
Y75255D01*
G01X554120Y76707D02*
X553758Y76937D01*
X553552Y77243D01*
X553500Y77588D01*
X553552Y77895D01*
X553810Y78202D01*
X554120Y78393D01*
X554430Y78432D01*
X554792Y78355D01*
X555050Y78087D01*
X555153Y77818D01*
Y77473D01*
G01Y77818D02*
X555308Y78048D01*
X555567Y78240D01*
X555877Y78317D01*
X556187Y78240D01*
X556445Y78048D01*
X556600Y77703D01*
X556548Y77358D01*
X556342Y77013D01*
G01X556083Y79922D02*
X556393Y80152D01*
X556548Y80420D01*
X556600Y80727D01*
X556497Y81110D01*
X556238Y81378D01*
X555928Y81455D01*
X555618Y81417D01*
X555360Y81263D01*
X554843Y80497D01*
X554482Y80152D01*
X553965Y79922D01*
X553500Y79845D01*
Y81455D01*
G01X564807Y199292D02*
X565037Y199447D01*
X565305Y199550D01*
X565612D01*
X565957Y199395D01*
X566225Y199137D01*
X566417Y198827D01*
X566570Y198310D01*
X566608Y197845D01*
X566532Y197380D01*
X566417Y197070D01*
X566187Y196760D01*
X565918Y196553D01*
X565650Y196450D01*
X565382D01*
X565113Y196553D01*
X564883Y196708D01*
X564692Y196915D01*
G01X563278Y199033D02*
X563048Y199343D01*
X562780Y199498D01*
X562473Y199550D01*
X562090Y199447D01*
X561822Y199188D01*
X561745Y198878D01*
X561783Y198568D01*
X561937Y198310D01*
X562703Y197793D01*
X563048Y197432D01*
X563278Y196915D01*
X563355Y196450D01*
X561745D01*
G01X560178Y197742D02*
X559910Y198103D01*
X559680Y198310D01*
X559373Y198413D01*
X559105Y198310D01*
X558913Y198103D01*
X558760Y197793D01*
X558722Y197432D01*
X558760Y197122D01*
X558913Y196812D01*
X559143Y196553D01*
X559412Y196450D01*
X559718Y196553D01*
X559987Y196863D01*
X560140Y197328D01*
X560178Y197845D01*
X560102Y198517D01*
X559987Y198878D01*
X559795Y199240D01*
X559527Y199498D01*
X559258Y199550D01*
X558990Y199447D01*
X558798Y199188D01*
G01X557078Y197742D02*
X556810Y198103D01*
X556580Y198310D01*
X556273Y198413D01*
X556005Y198310D01*
X555813Y198103D01*
X555660Y197793D01*
X555622Y197432D01*
X555660Y197122D01*
X555813Y196812D01*
X556043Y196553D01*
X556312Y196450D01*
X556618Y196553D01*
X556887Y196863D01*
X557040Y197328D01*
X557078Y197845D01*
X557002Y198517D01*
X556887Y198878D01*
X556695Y199240D01*
X556427Y199498D01*
X556158Y199550D01*
X555890Y199447D01*
X555698Y199188D01*
G01X578917Y197500D02*
Y200600D01*
X577958D01*
X577652Y200445D01*
X577460Y200238D01*
X577383Y199825D01*
X577460Y199412D01*
X577690Y199153D01*
X577958Y198998D01*
X578917D01*
G01X577958D02*
X577383Y197500D01*
G01X575778Y200083D02*
X575548Y200393D01*
X575280Y200548D01*
X574973Y200600D01*
X574590Y200497D01*
X574322Y200238D01*
X574245Y199928D01*
X574283Y199618D01*
X574437Y199360D01*
X575203Y198843D01*
X575548Y198482D01*
X575778Y197965D01*
X575855Y197500D01*
X574245D01*
G01X572793Y197965D02*
X572563Y197707D01*
X572295Y197552D01*
X571950Y197500D01*
X571605Y197603D01*
X571337Y197810D01*
X571145Y198172D01*
X571107Y198585D01*
X571183Y198998D01*
X571375Y199257D01*
X571643Y199463D01*
X571912Y199515D01*
X572180Y199463D01*
X572525Y199257D01*
X572410Y200600D01*
X571375D01*
G01X569693Y198120D02*
X569463Y197758D01*
X569157Y197552D01*
X568812Y197500D01*
X568505Y197552D01*
X568198Y197810D01*
X568007Y198120D01*
X567968Y198430D01*
X568045Y198792D01*
X568313Y199050D01*
X568582Y199153D01*
X568927D01*
G01X568582D02*
X568352Y199308D01*
X568160Y199567D01*
X568083Y199877D01*
X568160Y200187D01*
X568352Y200445D01*
X568697Y200600D01*
X569042Y200548D01*
X569387Y200342D01*
G01X562863Y213095D02*
X562605Y213402D01*
X562450Y213747D01*
Y214053D01*
X562605Y214360D01*
X562863Y214590D01*
X563225Y214705D01*
X563587Y214628D01*
X563897Y214437D01*
X564103Y214092D01*
X564207Y213632D01*
X564413Y213363D01*
X564775Y213248D01*
X565137Y213325D01*
X565395Y213517D01*
X565550Y213785D01*
Y214053D01*
X565447Y214322D01*
X565188Y214552D01*
G01X562450Y216233D02*
X565550D01*
Y217153D01*
X565395Y217460D01*
X565033Y217690D01*
X564620Y217767D01*
X564207Y217690D01*
X563897Y217498D01*
X563742Y217153D01*
Y216233D01*
G01X563070Y219257D02*
X562708Y219487D01*
X562502Y219793D01*
X562450Y220138D01*
X562502Y220445D01*
X562760Y220752D01*
X563070Y220943D01*
X563380Y220982D01*
X563742Y220905D01*
X564000Y220637D01*
X564103Y220368D01*
Y220023D01*
G01Y220368D02*
X564258Y220598D01*
X564517Y220790D01*
X564827Y220867D01*
X565137Y220790D01*
X565395Y220598D01*
X565550Y220253D01*
X565498Y219908D01*
X565292Y219563D01*
G01X566783Y230164D02*
X566938Y229934D01*
X567041Y229666D01*
Y229359D01*
X566886Y229014D01*
X566628Y228746D01*
X566318Y228554D01*
X565801Y228401D01*
X565336Y228363D01*
X564871Y228439D01*
X564561Y228554D01*
X564251Y228784D01*
X564044Y229053D01*
X563941Y229321D01*
Y229589D01*
X564044Y229858D01*
X564199Y230088D01*
X564406Y230279D01*
G01X566524Y231693D02*
X566834Y231923D01*
X566989Y232191D01*
X567041Y232498D01*
X566938Y232881D01*
X566679Y233149D01*
X566369Y233226D01*
X566059Y233188D01*
X565801Y233034D01*
X565284Y232268D01*
X564923Y231923D01*
X564406Y231693D01*
X563941Y231616D01*
Y233226D01*
G01X565233Y234793D02*
X565594Y235061D01*
X565801Y235291D01*
X565904Y235598D01*
X565801Y235866D01*
X565594Y236058D01*
X565284Y236211D01*
X564923Y236249D01*
X564613Y236211D01*
X564303Y236058D01*
X564044Y235828D01*
X563941Y235559D01*
X564044Y235253D01*
X564354Y234984D01*
X564819Y234831D01*
X565336Y234793D01*
X566008Y234869D01*
X566369Y234984D01*
X566731Y235176D01*
X566989Y235444D01*
X567041Y235713D01*
X566938Y235981D01*
X566679Y236173D01*
G01X564561Y237778D02*
X564199Y238008D01*
X563993Y238314D01*
X563941Y238659D01*
X563993Y238966D01*
X564251Y239273D01*
X564561Y239464D01*
X564871Y239503D01*
X565233Y239426D01*
X565491Y239158D01*
X565594Y238889D01*
Y238544D01*
G01Y238889D02*
X565749Y239119D01*
X566008Y239311D01*
X566318Y239388D01*
X566628Y239311D01*
X566886Y239119D01*
X567041Y238774D01*
X566989Y238429D01*
X566783Y238084D01*
G01X558450Y229083D02*
X561550D01*
Y230042D01*
X561395Y230348D01*
X561188Y230540D01*
X560775Y230617D01*
X560362Y230540D01*
X560103Y230310D01*
X559948Y230042D01*
Y229083D01*
G01Y230042D02*
X558450Y230617D01*
G01X561033Y232222D02*
X561343Y232452D01*
X561498Y232720D01*
X561550Y233027D01*
X561447Y233410D01*
X561188Y233678D01*
X560878Y233755D01*
X560568Y233717D01*
X560310Y233563D01*
X559793Y232797D01*
X559432Y232452D01*
X558915Y232222D01*
X558450Y232145D01*
Y233755D01*
G01Y236510D02*
X561550D01*
X559328Y235092D01*
Y237008D01*
G01X558812Y238498D02*
X558553Y238767D01*
X558450Y239073D01*
X558553Y239380D01*
X558863Y239648D01*
X559328Y239840D01*
X559793Y239917D01*
X560362D01*
X560827Y239840D01*
X561240Y239648D01*
X561447Y239418D01*
X561550Y239150D01*
X561447Y238843D01*
X561240Y238613D01*
X560930Y238460D01*
X560517Y238383D01*
X560155Y238460D01*
X559793Y238652D01*
X559587Y238882D01*
X559535Y239150D01*
X559638Y239457D01*
X559897Y239687D01*
X560362Y239917D01*
G01X553950Y229083D02*
X557050D01*
Y230042D01*
X556895Y230348D01*
X556688Y230540D01*
X556275Y230617D01*
X555862Y230540D01*
X555603Y230310D01*
X555448Y230042D01*
Y229083D01*
G01Y230042D02*
X553950Y230617D01*
G01X556533Y232222D02*
X556843Y232452D01*
X556998Y232720D01*
X557050Y233027D01*
X556947Y233410D01*
X556688Y233678D01*
X556378Y233755D01*
X556068Y233717D01*
X555810Y233563D01*
X555293Y232797D01*
X554932Y232452D01*
X554415Y232222D01*
X553950Y232145D01*
Y233755D01*
G01Y236510D02*
X557050D01*
X554828Y235092D01*
Y237008D01*
G01X555242Y238422D02*
X555603Y238690D01*
X555810Y238920D01*
X555913Y239227D01*
X555810Y239495D01*
X555603Y239687D01*
X555293Y239840D01*
X554932Y239878D01*
X554622Y239840D01*
X554312Y239687D01*
X554053Y239457D01*
X553950Y239188D01*
X554053Y238882D01*
X554363Y238613D01*
X554828Y238460D01*
X555345Y238422D01*
X556017Y238498D01*
X556378Y238613D01*
X556740Y238805D01*
X556998Y239073D01*
X557050Y239342D01*
X556947Y239610D01*
X556688Y239802D01*
G01X568450Y229083D02*
X571550D01*
Y230042D01*
X571395Y230348D01*
X571188Y230540D01*
X570775Y230617D01*
X570362Y230540D01*
X570103Y230310D01*
X569948Y230042D01*
Y229083D01*
G01Y230042D02*
X568450Y230617D01*
G01X571033Y232222D02*
X571343Y232452D01*
X571498Y232720D01*
X571550Y233027D01*
X571447Y233410D01*
X571188Y233678D01*
X570878Y233755D01*
X570568Y233717D01*
X570310Y233563D01*
X569793Y232797D01*
X569432Y232452D01*
X568915Y232222D01*
X568450Y232145D01*
Y233755D01*
G01X568915Y235207D02*
X568657Y235437D01*
X568502Y235705D01*
X568450Y236050D01*
X568553Y236395D01*
X568760Y236663D01*
X569122Y236855D01*
X569535Y236893D01*
X569948Y236817D01*
X570207Y236625D01*
X570413Y236357D01*
X570465Y236088D01*
X570413Y235820D01*
X570207Y235475D01*
X571550Y235590D01*
Y236625D01*
G01X571033Y238422D02*
X571343Y238652D01*
X571498Y238920D01*
X571550Y239227D01*
X571447Y239610D01*
X571188Y239878D01*
X570878Y239955D01*
X570568Y239917D01*
X570310Y239763D01*
X569793Y238997D01*
X569432Y238652D01*
X568915Y238422D01*
X568450Y238345D01*
Y239955D01*
G01X568578Y262083D02*
X568348Y262393D01*
X568080Y262548D01*
X567773Y262600D01*
X567390Y262497D01*
X567122Y262238D01*
X567045Y261928D01*
X567083Y261618D01*
X567237Y261360D01*
X568003Y260843D01*
X568348Y260482D01*
X568578Y259965D01*
X568655Y259500D01*
X567045D01*
G01X572257Y270342D02*
X572487Y270497D01*
X572755Y270600D01*
X573062D01*
X573407Y270445D01*
X573675Y270187D01*
X573867Y269877D01*
X574020Y269360D01*
X574058Y268895D01*
X573982Y268430D01*
X573867Y268120D01*
X573637Y267810D01*
X573368Y267603D01*
X573100Y267500D01*
X572832D01*
X572563Y267603D01*
X572333Y267758D01*
X572142Y267965D01*
G01X570767Y267500D02*
Y270600D01*
X569808D01*
X569502Y270445D01*
X569310Y270238D01*
X569233Y269825D01*
X569310Y269412D01*
X569540Y269153D01*
X569808Y268998D01*
X570767D01*
G01X569808D02*
X569233Y267500D01*
G01X566977D02*
X566900Y268172D01*
X566785Y268740D01*
X566632Y269257D01*
X566440Y269825D01*
X566133Y270600D01*
X567667D01*
G01X568359Y274270D02*
X568129Y273908D01*
X567823Y273702D01*
X567478Y273650D01*
X567171Y273702D01*
X566864Y273960D01*
X566673Y274270D01*
X566634Y274580D01*
X566711Y274942D01*
X566979Y275200D01*
X567248Y275303D01*
X567593D01*
G01X567248D02*
X567018Y275458D01*
X566826Y275717D01*
X566749Y276027D01*
X566826Y276337D01*
X567018Y276595D01*
X567363Y276750D01*
X567708Y276698D01*
X568053Y276492D01*
G01X567578Y289583D02*
X567348Y289893D01*
X567080Y290048D01*
X566773Y290100D01*
X566390Y289997D01*
X566122Y289738D01*
X566045Y289428D01*
X566083Y289118D01*
X566237Y288860D01*
X567003Y288343D01*
X567348Y287982D01*
X567578Y287465D01*
X567655Y287000D01*
X566045D01*
G01X567859Y303270D02*
X567629Y302908D01*
X567323Y302702D01*
X566978Y302650D01*
X566671Y302702D01*
X566364Y302960D01*
X566173Y303270D01*
X566134Y303580D01*
X566211Y303942D01*
X566479Y304200D01*
X566748Y304303D01*
X567093D01*
G01X566748D02*
X566518Y304458D01*
X566326Y304717D01*
X566249Y305027D01*
X566326Y305337D01*
X566518Y305595D01*
X566863Y305750D01*
X567208Y305698D01*
X567553Y305492D01*
G01X565950Y405083D02*
X569050D01*
Y406042D01*
X568895Y406348D01*
X568688Y406540D01*
X568275Y406617D01*
X567862Y406540D01*
X567603Y406310D01*
X567448Y406042D01*
Y405083D01*
G01Y406042D02*
X565950Y406617D01*
G01Y408950D02*
X569050D01*
X568430Y408490D01*
G01X565950D02*
Y409410D01*
G01Y412050D02*
X566002Y412318D01*
X566157Y412625D01*
X566415Y412817D01*
X566777Y412893D01*
X567138Y412817D01*
X567448Y412587D01*
X567603Y412242D01*
Y411858D01*
X567707Y411628D01*
X567965Y411437D01*
X568327Y411360D01*
X568688Y411475D01*
X568947Y411743D01*
X569050Y412050D01*
X568947Y412357D01*
X568688Y412625D01*
X568327Y412740D01*
X567965Y412663D01*
X567707Y412472D01*
X567603Y412242D01*
Y411858D01*
X567448Y411513D01*
X567138Y411283D01*
X566777Y411207D01*
X566415Y411283D01*
X566157Y411475D01*
X566002Y411782D01*
X565950Y412050D01*
G01X569050Y415150D02*
X568947Y414843D01*
X568688Y414613D01*
X568378Y414460D01*
X567965Y414345D01*
X567500Y414307D01*
X567035Y414345D01*
X566622Y414460D01*
X566312Y414613D01*
X566053Y414843D01*
X565950Y415150D01*
X566053Y415457D01*
X566312Y415687D01*
X566622Y415840D01*
X567035Y415955D01*
X567500Y415993D01*
X567965Y415955D01*
X568378Y415840D01*
X568688Y415687D01*
X568947Y415457D01*
X569050Y415150D01*
G01X565450Y418583D02*
X568550D01*
Y419542D01*
X568395Y419848D01*
X568188Y420040D01*
X567775Y420117D01*
X567362Y420040D01*
X567103Y419810D01*
X566948Y419542D01*
Y418583D01*
G01Y419542D02*
X565450Y420117D01*
G01X568033Y421722D02*
X568343Y421952D01*
X568498Y422220D01*
X568550Y422527D01*
X568447Y422910D01*
X568188Y423178D01*
X567878Y423255D01*
X567568Y423217D01*
X567310Y423063D01*
X566793Y422297D01*
X566432Y421952D01*
X565915Y421722D01*
X565450Y421645D01*
Y423255D01*
G01X565915Y424707D02*
X565657Y424937D01*
X565502Y425205D01*
X565450Y425550D01*
X565553Y425895D01*
X565760Y426163D01*
X566122Y426355D01*
X566535Y426393D01*
X566948Y426317D01*
X567207Y426125D01*
X567413Y425857D01*
X567465Y425588D01*
X567413Y425320D01*
X567207Y424975D01*
X568550Y425090D01*
Y426125D01*
G01X565812Y427998D02*
X565553Y428267D01*
X565450Y428573D01*
X565553Y428880D01*
X565863Y429148D01*
X566328Y429340D01*
X566793Y429417D01*
X567362D01*
X567827Y429340D01*
X568240Y429148D01*
X568447Y428918D01*
X568550Y428650D01*
X568447Y428343D01*
X568240Y428113D01*
X567930Y427960D01*
X567517Y427883D01*
X567155Y427960D01*
X566793Y428152D01*
X566587Y428382D01*
X566535Y428650D01*
X566638Y428957D01*
X566897Y429187D01*
X567362Y429417D01*
G01X553950Y418583D02*
X557050D01*
Y419542D01*
X556895Y419848D01*
X556688Y420040D01*
X556275Y420117D01*
X555862Y420040D01*
X555603Y419810D01*
X555448Y419542D01*
Y418583D01*
G01Y419542D02*
X553950Y420117D01*
G01X556533Y421722D02*
X556843Y421952D01*
X556998Y422220D01*
X557050Y422527D01*
X556947Y422910D01*
X556688Y423178D01*
X556378Y423255D01*
X556068Y423217D01*
X555810Y423063D01*
X555293Y422297D01*
X554932Y421952D01*
X554415Y421722D01*
X553950Y421645D01*
Y423255D01*
G01X554415Y424707D02*
X554157Y424937D01*
X554002Y425205D01*
X553950Y425550D01*
X554053Y425895D01*
X554260Y426163D01*
X554622Y426355D01*
X555035Y426393D01*
X555448Y426317D01*
X555707Y426125D01*
X555913Y425857D01*
X555965Y425588D01*
X555913Y425320D01*
X555707Y424975D01*
X557050Y425090D01*
Y426125D01*
G01X553950Y428650D02*
X554002Y428918D01*
X554157Y429225D01*
X554415Y429417D01*
X554777Y429493D01*
X555138Y429417D01*
X555448Y429187D01*
X555603Y428842D01*
Y428458D01*
X555707Y428228D01*
X555965Y428037D01*
X556327Y427960D01*
X556688Y428075D01*
X556947Y428343D01*
X557050Y428650D01*
X556947Y428957D01*
X556688Y429225D01*
X556327Y429340D01*
X555965Y429263D01*
X555707Y429072D01*
X555603Y428842D01*
Y428458D01*
X555448Y428113D01*
X555138Y427883D01*
X554777Y427807D01*
X554415Y427883D01*
X554157Y428075D01*
X554002Y428382D01*
X553950Y428650D01*
G01X583792Y73693D02*
X583947Y73463D01*
X584050Y73195D01*
Y72888D01*
X583895Y72543D01*
X583637Y72275D01*
X583327Y72083D01*
X582810Y71930D01*
X582345Y71892D01*
X581880Y71968D01*
X581570Y72083D01*
X581260Y72313D01*
X581053Y72582D01*
X580950Y72850D01*
Y73118D01*
X581053Y73387D01*
X581208Y73617D01*
X581415Y73808D01*
G01X583533Y75222D02*
X583843Y75452D01*
X583998Y75720D01*
X584050Y76027D01*
X583947Y76410D01*
X583688Y76678D01*
X583378Y76755D01*
X583068Y76717D01*
X582810Y76563D01*
X582293Y75797D01*
X581932Y75452D01*
X581415Y75222D01*
X580950Y75145D01*
Y76755D01*
G01X581312Y78398D02*
X581053Y78667D01*
X580950Y78973D01*
X581053Y79280D01*
X581363Y79548D01*
X581828Y79740D01*
X582293Y79817D01*
X582862D01*
X583327Y79740D01*
X583740Y79548D01*
X583947Y79318D01*
X584050Y79050D01*
X583947Y78743D01*
X583740Y78513D01*
X583430Y78360D01*
X583017Y78283D01*
X582655Y78360D01*
X582293Y78552D01*
X582087Y78782D01*
X582035Y79050D01*
X582138Y79357D01*
X582397Y79587D01*
X582862Y79817D01*
G01X581570Y81307D02*
X581208Y81537D01*
X581002Y81843D01*
X580950Y82188D01*
X581002Y82495D01*
X581260Y82802D01*
X581570Y82993D01*
X581880Y83032D01*
X582242Y82955D01*
X582500Y82687D01*
X582603Y82418D01*
Y82073D01*
G01Y82418D02*
X582758Y82648D01*
X583017Y82840D01*
X583327Y82917D01*
X583637Y82840D01*
X583895Y82648D01*
X584050Y82303D01*
X583998Y81958D01*
X583792Y81613D01*
G01X575950Y72083D02*
X579050D01*
Y73042D01*
X578895Y73348D01*
X578688Y73540D01*
X578275Y73617D01*
X577862Y73540D01*
X577603Y73310D01*
X577448Y73042D01*
Y72083D01*
G01Y73042D02*
X575950Y73617D01*
G01X578533Y75222D02*
X578843Y75452D01*
X578998Y75720D01*
X579050Y76027D01*
X578947Y76410D01*
X578688Y76678D01*
X578378Y76755D01*
X578068Y76717D01*
X577810Y76563D01*
X577293Y75797D01*
X576932Y75452D01*
X576415Y75222D01*
X575950Y75145D01*
Y76755D01*
G01X578533Y78322D02*
X578843Y78552D01*
X578998Y78820D01*
X579050Y79127D01*
X578947Y79510D01*
X578688Y79778D01*
X578378Y79855D01*
X578068Y79817D01*
X577810Y79663D01*
X577293Y78897D01*
X576932Y78552D01*
X576415Y78322D01*
X575950Y78245D01*
Y79855D01*
G01X576415Y81307D02*
X576157Y81537D01*
X576002Y81805D01*
X575950Y82150D01*
X576053Y82495D01*
X576260Y82763D01*
X576622Y82955D01*
X577035Y82993D01*
X577448Y82917D01*
X577707Y82725D01*
X577913Y82457D01*
X577965Y82188D01*
X577913Y81920D01*
X577707Y81575D01*
X579050Y81690D01*
Y82725D01*
G01X575500Y59583D02*
X578600D01*
Y60542D01*
X578445Y60848D01*
X578238Y61040D01*
X577825Y61117D01*
X577412Y61040D01*
X577153Y60810D01*
X576998Y60542D01*
Y59583D01*
G01Y60542D02*
X575500Y61117D01*
G01X578083Y62722D02*
X578393Y62952D01*
X578548Y63220D01*
X578600Y63527D01*
X578497Y63910D01*
X578238Y64178D01*
X577928Y64255D01*
X577618Y64217D01*
X577360Y64063D01*
X576843Y63297D01*
X576482Y62952D01*
X575965Y62722D01*
X575500Y62645D01*
Y64255D01*
G01X578083Y65822D02*
X578393Y66052D01*
X578548Y66320D01*
X578600Y66627D01*
X578497Y67010D01*
X578238Y67278D01*
X577928Y67355D01*
X577618Y67317D01*
X577360Y67163D01*
X576843Y66397D01*
X576482Y66052D01*
X575965Y65822D01*
X575500Y65745D01*
Y67355D01*
G01Y69573D02*
X576172Y69650D01*
X576740Y69765D01*
X577257Y69918D01*
X577825Y70110D01*
X578600Y70417D01*
Y68883D01*
G01X573850Y229083D02*
X576950D01*
Y230042D01*
X576795Y230348D01*
X576588Y230540D01*
X576175Y230617D01*
X575762Y230540D01*
X575503Y230310D01*
X575348Y230042D01*
Y229083D01*
G01Y230042D02*
X573850Y230617D01*
G01X576433Y232222D02*
X576743Y232452D01*
X576898Y232720D01*
X576950Y233027D01*
X576847Y233410D01*
X576588Y233678D01*
X576278Y233755D01*
X575968Y233717D01*
X575710Y233563D01*
X575193Y232797D01*
X574832Y232452D01*
X574315Y232222D01*
X573850Y232145D01*
Y233755D01*
G01X574315Y235207D02*
X574057Y235437D01*
X573902Y235705D01*
X573850Y236050D01*
X573953Y236395D01*
X574160Y236663D01*
X574522Y236855D01*
X574935Y236893D01*
X575348Y236817D01*
X575607Y236625D01*
X575813Y236357D01*
X575865Y236088D01*
X575813Y235820D01*
X575607Y235475D01*
X576950Y235590D01*
Y236625D01*
G01X573850Y239150D02*
X576950D01*
X576330Y238690D01*
G01X573850D02*
Y239610D01*
G01X574657Y273750D02*
Y276850D01*
X576075Y274628D01*
X574159D01*
G01X572092Y294343D02*
X572247Y294113D01*
X572350Y293845D01*
Y293538D01*
X572195Y293193D01*
X571937Y292925D01*
X571627Y292733D01*
X571110Y292580D01*
X570645Y292542D01*
X570180Y292618D01*
X569870Y292733D01*
X569560Y292963D01*
X569353Y293232D01*
X569250Y293500D01*
Y293768D01*
X569353Y294037D01*
X569508Y294267D01*
X569715Y294458D01*
G01X569250Y295833D02*
X572350D01*
Y296792D01*
X572195Y297098D01*
X571988Y297290D01*
X571575Y297367D01*
X571162Y297290D01*
X570903Y297060D01*
X570748Y296792D01*
Y295833D01*
G01Y296792D02*
X569250Y297367D01*
G01X570542Y298972D02*
X570903Y299240D01*
X571110Y299470D01*
X571213Y299777D01*
X571110Y300045D01*
X570903Y300237D01*
X570593Y300390D01*
X570232Y300428D01*
X569922Y300390D01*
X569612Y300237D01*
X569353Y300007D01*
X569250Y299738D01*
X569353Y299432D01*
X569663Y299163D01*
X570128Y299010D01*
X570645Y298972D01*
X571317Y299048D01*
X571678Y299163D01*
X572040Y299355D01*
X572298Y299623D01*
X572350Y299892D01*
X572247Y300160D01*
X571988Y300352D01*
G01X574157Y302750D02*
Y305850D01*
X575575Y303628D01*
X573659D01*
G01X577967Y390182D02*
Y393282D01*
X577008D01*
X576702Y393127D01*
X576510Y392920D01*
X576433Y392507D01*
X576510Y392094D01*
X576740Y391835D01*
X577008Y391680D01*
X577967D01*
G01X577008D02*
X576433Y390182D01*
G01X574100D02*
Y393282D01*
X574560Y392662D01*
G01Y390182D02*
X573640D01*
G01X571728Y391474D02*
X571460Y391835D01*
X571230Y392042D01*
X570923Y392145D01*
X570655Y392042D01*
X570463Y391835D01*
X570310Y391525D01*
X570272Y391164D01*
X570310Y390854D01*
X570463Y390544D01*
X570693Y390285D01*
X570962Y390182D01*
X571268Y390285D01*
X571537Y390595D01*
X571690Y391060D01*
X571728Y391577D01*
X571652Y392249D01*
X571537Y392610D01*
X571345Y392972D01*
X571077Y393230D01*
X570808Y393282D01*
X570540Y393179D01*
X570348Y392920D01*
G01X577967Y385182D02*
Y388282D01*
X577008D01*
X576702Y388127D01*
X576510Y387920D01*
X576433Y387507D01*
X576510Y387094D01*
X576740Y386835D01*
X577008Y386680D01*
X577967D01*
G01X577008D02*
X576433Y385182D01*
G01X574100D02*
Y388282D01*
X574560Y387662D01*
G01Y385182D02*
X573640D01*
G01X571000Y388282D02*
X571307Y388179D01*
X571537Y387920D01*
X571690Y387610D01*
X571805Y387197D01*
X571843Y386732D01*
X571805Y386267D01*
X571690Y385854D01*
X571537Y385544D01*
X571307Y385285D01*
X571000Y385182D01*
X570693Y385285D01*
X570463Y385544D01*
X570310Y385854D01*
X570195Y386267D01*
X570157Y386732D01*
X570195Y387197D01*
X570310Y387610D01*
X570463Y387920D01*
X570693Y388179D01*
X571000Y388282D01*
G01X584417Y405950D02*
Y409050D01*
X583458D01*
X583152Y408895D01*
X582960Y408688D01*
X582883Y408275D01*
X582960Y407862D01*
X583190Y407603D01*
X583458Y407448D01*
X584417D01*
G01X583458D02*
X582883Y405950D01*
G01X581278Y408533D02*
X581048Y408843D01*
X580780Y408998D01*
X580473Y409050D01*
X580090Y408947D01*
X579822Y408688D01*
X579745Y408378D01*
X579783Y408068D01*
X579937Y407810D01*
X580703Y407293D01*
X581048Y406932D01*
X581278Y406415D01*
X581355Y405950D01*
X579745D01*
G01X578178Y407242D02*
X577910Y407603D01*
X577680Y407810D01*
X577373Y407913D01*
X577105Y407810D01*
X576913Y407603D01*
X576760Y407293D01*
X576722Y406932D01*
X576760Y406622D01*
X576913Y406312D01*
X577143Y406053D01*
X577412Y405950D01*
X577718Y406053D01*
X577987Y406363D01*
X578140Y406828D01*
X578178Y407345D01*
X578102Y408017D01*
X577987Y408378D01*
X577795Y408740D01*
X577527Y408998D01*
X577258Y409050D01*
X576990Y408947D01*
X576798Y408688D01*
G01X575078Y408533D02*
X574848Y408843D01*
X574580Y408998D01*
X574273Y409050D01*
X573890Y408947D01*
X573622Y408688D01*
X573545Y408378D01*
X573583Y408068D01*
X573737Y407810D01*
X574503Y407293D01*
X574848Y406932D01*
X575078Y406415D01*
X575155Y405950D01*
X573545D01*
G01X577450Y418583D02*
X580550D01*
Y419542D01*
X580395Y419848D01*
X580188Y420040D01*
X579775Y420117D01*
X579362Y420040D01*
X579103Y419810D01*
X578948Y419542D01*
Y418583D01*
G01Y419542D02*
X577450Y420117D01*
G01X580033Y421722D02*
X580343Y421952D01*
X580498Y422220D01*
X580550Y422527D01*
X580447Y422910D01*
X580188Y423178D01*
X579878Y423255D01*
X579568Y423217D01*
X579310Y423063D01*
X578793Y422297D01*
X578432Y421952D01*
X577915Y421722D01*
X577450Y421645D01*
Y423255D01*
G01X578742Y424822D02*
X579103Y425090D01*
X579310Y425320D01*
X579413Y425627D01*
X579310Y425895D01*
X579103Y426087D01*
X578793Y426240D01*
X578432Y426278D01*
X578122Y426240D01*
X577812Y426087D01*
X577553Y425857D01*
X577450Y425588D01*
X577553Y425282D01*
X577863Y425013D01*
X578328Y424860D01*
X578845Y424822D01*
X579517Y424898D01*
X579878Y425013D01*
X580240Y425205D01*
X580498Y425473D01*
X580550Y425742D01*
X580447Y426010D01*
X580188Y426202D01*
G01X577450Y428650D02*
X580550D01*
X579930Y428190D01*
G01X577450D02*
Y429110D01*
G01X584417Y410450D02*
Y413550D01*
X583458D01*
X583152Y413395D01*
X582960Y413188D01*
X582883Y412775D01*
X582960Y412362D01*
X583190Y412103D01*
X583458Y411948D01*
X584417D01*
G01X583458D02*
X582883Y410450D01*
G01X581278Y413033D02*
X581048Y413343D01*
X580780Y413498D01*
X580473Y413550D01*
X580090Y413447D01*
X579822Y413188D01*
X579745Y412878D01*
X579783Y412568D01*
X579937Y412310D01*
X580703Y411793D01*
X581048Y411432D01*
X581278Y410915D01*
X581355Y410450D01*
X579745D01*
G01X578293Y410915D02*
X578063Y410657D01*
X577795Y410502D01*
X577450Y410450D01*
X577105Y410553D01*
X576837Y410760D01*
X576645Y411122D01*
X576607Y411535D01*
X576683Y411948D01*
X576875Y412207D01*
X577143Y412413D01*
X577412Y412465D01*
X577680Y412413D01*
X578025Y412207D01*
X577910Y413550D01*
X576875D01*
G01X575078Y411742D02*
X574810Y412103D01*
X574580Y412310D01*
X574273Y412413D01*
X574005Y412310D01*
X573813Y412103D01*
X573660Y411793D01*
X573622Y411432D01*
X573660Y411122D01*
X573813Y410812D01*
X574043Y410553D01*
X574312Y410450D01*
X574618Y410553D01*
X574887Y410863D01*
X575040Y411328D01*
X575078Y411845D01*
X575002Y412517D01*
X574887Y412878D01*
X574695Y413240D01*
X574427Y413498D01*
X574158Y413550D01*
X573890Y413447D01*
X573698Y413188D01*
G01X596450Y136583D02*
X599550D01*
Y137542D01*
X599395Y137848D01*
X599188Y138040D01*
X598775Y138117D01*
X598362Y138040D01*
X598103Y137810D01*
X597948Y137542D01*
Y136583D01*
G01Y137542D02*
X596450Y138117D01*
G01Y140910D02*
X599550D01*
X597328Y139492D01*
Y141408D01*
G01X597070Y142707D02*
X596708Y142937D01*
X596502Y143243D01*
X596450Y143588D01*
X596502Y143895D01*
X596760Y144202D01*
X597070Y144393D01*
X597380Y144432D01*
X597742Y144355D01*
X598000Y144087D01*
X598103Y143818D01*
Y143473D01*
G01Y143818D02*
X598258Y144048D01*
X598517Y144240D01*
X598827Y144317D01*
X599137Y144240D01*
X599395Y144048D01*
X599550Y143703D01*
X599498Y143358D01*
X599292Y143013D01*
G01X596450Y146650D02*
X599550D01*
X598930Y146190D01*
G01X596450D02*
Y147110D01*
G01Y149083D02*
X599550D01*
Y150042D01*
X599395Y150348D01*
X599188Y150540D01*
X598775Y150617D01*
X598362Y150540D01*
X598103Y150310D01*
X597948Y150042D01*
Y149083D01*
G01Y150042D02*
X596450Y150617D01*
G01Y153410D02*
X599550D01*
X597328Y151992D01*
Y153908D01*
G01X597070Y155207D02*
X596708Y155437D01*
X596502Y155743D01*
X596450Y156088D01*
X596502Y156395D01*
X596760Y156702D01*
X597070Y156893D01*
X597380Y156932D01*
X597742Y156855D01*
X598000Y156587D01*
X598103Y156318D01*
Y155973D01*
G01Y156318D02*
X598258Y156548D01*
X598517Y156740D01*
X598827Y156817D01*
X599137Y156740D01*
X599395Y156548D01*
X599550Y156203D01*
X599498Y155858D01*
X599292Y155513D01*
G01X599033Y158422D02*
X599343Y158652D01*
X599498Y158920D01*
X599550Y159227D01*
X599447Y159610D01*
X599188Y159878D01*
X598878Y159955D01*
X598568Y159917D01*
X598310Y159763D01*
X597793Y158997D01*
X597432Y158652D01*
X596915Y158422D01*
X596450Y158345D01*
Y159955D01*
G01Y161583D02*
X599550D01*
Y162542D01*
X599395Y162848D01*
X599188Y163040D01*
X598775Y163117D01*
X598362Y163040D01*
X598103Y162810D01*
X597948Y162542D01*
Y161583D01*
G01Y162542D02*
X596450Y163117D01*
G01Y165910D02*
X599550D01*
X597328Y164492D01*
Y166408D01*
G01X597070Y167707D02*
X596708Y167937D01*
X596502Y168243D01*
X596450Y168588D01*
X596502Y168895D01*
X596760Y169202D01*
X597070Y169393D01*
X597380Y169432D01*
X597742Y169355D01*
X598000Y169087D01*
X598103Y168818D01*
Y168473D01*
G01Y168818D02*
X598258Y169048D01*
X598517Y169240D01*
X598827Y169317D01*
X599137Y169240D01*
X599395Y169048D01*
X599550Y168703D01*
X599498Y168358D01*
X599292Y168013D01*
G01X597070Y170807D02*
X596708Y171037D01*
X596502Y171343D01*
X596450Y171688D01*
X596502Y171995D01*
X596760Y172302D01*
X597070Y172493D01*
X597380Y172532D01*
X597742Y172455D01*
X598000Y172187D01*
X598103Y171918D01*
Y171573D01*
G01Y171918D02*
X598258Y172148D01*
X598517Y172340D01*
X598827Y172417D01*
X599137Y172340D01*
X599395Y172148D01*
X599550Y171803D01*
X599498Y171458D01*
X599292Y171113D01*
G01X596450Y173583D02*
X599550D01*
Y174542D01*
X599395Y174848D01*
X599188Y175040D01*
X598775Y175117D01*
X598362Y175040D01*
X598103Y174810D01*
X597948Y174542D01*
Y173583D01*
G01Y174542D02*
X596450Y175117D01*
G01Y177910D02*
X599550D01*
X597328Y176492D01*
Y178408D01*
G01X597070Y179707D02*
X596708Y179937D01*
X596502Y180243D01*
X596450Y180588D01*
X596502Y180895D01*
X596760Y181202D01*
X597070Y181393D01*
X597380Y181432D01*
X597742Y181355D01*
X598000Y181087D01*
X598103Y180818D01*
Y180473D01*
G01Y180818D02*
X598258Y181048D01*
X598517Y181240D01*
X598827Y181317D01*
X599137Y181240D01*
X599395Y181048D01*
X599550Y180703D01*
X599498Y180358D01*
X599292Y180013D01*
G01X596450Y184110D02*
X599550D01*
X597328Y182692D01*
Y184608D01*
G01X590352Y189098D02*
X593452D01*
Y190057D01*
X593297Y190363D01*
X593090Y190555D01*
X592677Y190632D01*
X592264Y190555D01*
X592005Y190325D01*
X591850Y190057D01*
Y189098D01*
G01Y190057D02*
X590352Y190632D01*
G01X591644Y192237D02*
X592005Y192505D01*
X592212Y192735D01*
X592315Y193042D01*
X592212Y193310D01*
X592005Y193502D01*
X591695Y193655D01*
X591334Y193693D01*
X591024Y193655D01*
X590714Y193502D01*
X590455Y193272D01*
X590352Y193003D01*
X590455Y192697D01*
X590765Y192428D01*
X591230Y192275D01*
X591747Y192237D01*
X592419Y192313D01*
X592780Y192428D01*
X593142Y192620D01*
X593400Y192888D01*
X593452Y193157D01*
X593349Y193425D01*
X593090Y193617D01*
G01X590352Y196525D02*
X593452D01*
X591230Y195107D01*
Y197023D01*
G01X595352Y189098D02*
X598452D01*
Y190057D01*
X598297Y190363D01*
X598090Y190555D01*
X597677Y190632D01*
X597264Y190555D01*
X597005Y190325D01*
X596850Y190057D01*
Y189098D01*
G01Y190057D02*
X595352Y190632D01*
G01X596644Y192237D02*
X597005Y192505D01*
X597212Y192735D01*
X597315Y193042D01*
X597212Y193310D01*
X597005Y193502D01*
X596695Y193655D01*
X596334Y193693D01*
X596024Y193655D01*
X595714Y193502D01*
X595455Y193272D01*
X595352Y193003D01*
X595455Y192697D01*
X595765Y192428D01*
X596230Y192275D01*
X596747Y192237D01*
X597419Y192313D01*
X597780Y192428D01*
X598142Y192620D01*
X598400Y192888D01*
X598452Y193157D01*
X598349Y193425D01*
X598090Y193617D01*
G01X595714Y195413D02*
X595455Y195682D01*
X595352Y195988D01*
X595455Y196295D01*
X595765Y196563D01*
X596230Y196755D01*
X596695Y196832D01*
X597264D01*
X597729Y196755D01*
X598142Y196563D01*
X598349Y196333D01*
X598452Y196065D01*
X598349Y195758D01*
X598142Y195528D01*
X597832Y195375D01*
X597419Y195298D01*
X597057Y195375D01*
X596695Y195567D01*
X596489Y195797D01*
X596437Y196065D01*
X596540Y196372D01*
X596799Y196602D01*
X597264Y196832D01*
G01X600352Y187548D02*
X603452D01*
Y188507D01*
X603297Y188813D01*
X603090Y189005D01*
X602677Y189082D01*
X602264Y189005D01*
X602005Y188775D01*
X601850Y188507D01*
Y187548D01*
G01Y188507D02*
X600352Y189082D01*
G01X600972Y190572D02*
X600610Y190802D01*
X600404Y191108D01*
X600352Y191453D01*
X600404Y191760D01*
X600662Y192067D01*
X600972Y192258D01*
X601282Y192297D01*
X601644Y192220D01*
X601902Y191952D01*
X602005Y191683D01*
Y191338D01*
G01Y191683D02*
X602160Y191913D01*
X602419Y192105D01*
X602729Y192182D01*
X603039Y192105D01*
X603297Y191913D01*
X603452Y191568D01*
X603400Y191223D01*
X603194Y190878D01*
G01X603452Y194515D02*
X603349Y194208D01*
X603090Y193978D01*
X602780Y193825D01*
X602367Y193710D01*
X601902Y193672D01*
X601437Y193710D01*
X601024Y193825D01*
X600714Y193978D01*
X600455Y194208D01*
X600352Y194515D01*
X600455Y194822D01*
X600714Y195052D01*
X601024Y195205D01*
X601437Y195320D01*
X601902Y195358D01*
X602367Y195320D01*
X602780Y195205D01*
X603090Y195052D01*
X603349Y194822D01*
X603452Y194515D01*
G01Y197615D02*
X603349Y197308D01*
X603090Y197078D01*
X602780Y196925D01*
X602367Y196810D01*
X601902Y196772D01*
X601437Y196810D01*
X601024Y196925D01*
X600714Y197078D01*
X600455Y197308D01*
X600352Y197615D01*
X600455Y197922D01*
X600714Y198152D01*
X601024Y198305D01*
X601437Y198420D01*
X601902Y198458D01*
X602367Y198420D01*
X602780Y198305D01*
X603090Y198152D01*
X603349Y197922D01*
X603452Y197615D01*
G01X605367Y260982D02*
Y264082D01*
X604408D01*
X604102Y263927D01*
X603910Y263720D01*
X603833Y263307D01*
X603910Y262894D01*
X604140Y262635D01*
X604408Y262480D01*
X605367D01*
G01X604408D02*
X603833Y260982D01*
G01X601500D02*
X601232Y261034D01*
X600925Y261189D01*
X600733Y261447D01*
X600657Y261809D01*
X600733Y262170D01*
X600963Y262480D01*
X601308Y262635D01*
X601692D01*
X601922Y262739D01*
X602113Y262997D01*
X602190Y263359D01*
X602075Y263720D01*
X601807Y263979D01*
X601500Y264082D01*
X601193Y263979D01*
X600925Y263720D01*
X600810Y263359D01*
X600887Y262997D01*
X601078Y262739D01*
X601308Y262635D01*
X601692D01*
X602037Y262480D01*
X602267Y262170D01*
X602343Y261809D01*
X602267Y261447D01*
X602075Y261189D01*
X601768Y261034D01*
X601500Y260982D01*
G01X598400D02*
Y264082D01*
X598860Y263462D01*
G01Y260982D02*
X597940D01*
G01X605367Y278482D02*
Y281582D01*
X604408D01*
X604102Y281427D01*
X603910Y281220D01*
X603833Y280807D01*
X603910Y280394D01*
X604140Y280135D01*
X604408Y279980D01*
X605367D01*
G01X604408D02*
X603833Y278482D01*
G01X601500D02*
X601232Y278534D01*
X600925Y278689D01*
X600733Y278947D01*
X600657Y279309D01*
X600733Y279670D01*
X600963Y279980D01*
X601308Y280135D01*
X601692D01*
X601922Y280239D01*
X602113Y280497D01*
X602190Y280859D01*
X602075Y281220D01*
X601807Y281479D01*
X601500Y281582D01*
X601193Y281479D01*
X600925Y281220D01*
X600810Y280859D01*
X600887Y280497D01*
X601078Y280239D01*
X601308Y280135D01*
X601692D01*
X602037Y279980D01*
X602267Y279670D01*
X602343Y279309D01*
X602267Y278947D01*
X602075Y278689D01*
X601768Y278534D01*
X601500Y278482D01*
G01X599128Y281065D02*
X598898Y281375D01*
X598630Y281530D01*
X598323Y281582D01*
X597940Y281479D01*
X597672Y281220D01*
X597595Y280910D01*
X597633Y280600D01*
X597787Y280342D01*
X598553Y279825D01*
X598898Y279464D01*
X599128Y278947D01*
X599205Y278482D01*
X597595D01*
G01X600950Y405583D02*
X604050D01*
Y406542D01*
X603895Y406848D01*
X603688Y407040D01*
X603275Y407117D01*
X602862Y407040D01*
X602603Y406810D01*
X602448Y406542D01*
Y405583D01*
G01Y406542D02*
X600950Y407117D01*
G01Y409450D02*
X604050D01*
X603430Y408990D01*
G01X600950D02*
Y409910D01*
G01Y412550D02*
X604050D01*
X603430Y412090D01*
G01X600950D02*
Y413010D01*
G01X601312Y414998D02*
X601053Y415267D01*
X600950Y415573D01*
X601053Y415880D01*
X601363Y416148D01*
X601828Y416340D01*
X602293Y416417D01*
X602862D01*
X603327Y416340D01*
X603740Y416148D01*
X603947Y415918D01*
X604050Y415650D01*
X603947Y415343D01*
X603740Y415113D01*
X603430Y414960D01*
X603017Y414883D01*
X602655Y414960D01*
X602293Y415152D01*
X602087Y415382D01*
X602035Y415650D01*
X602138Y415957D01*
X602397Y416187D01*
X602862Y416417D01*
G01X589450Y405583D02*
X592550D01*
Y406542D01*
X592395Y406848D01*
X592188Y407040D01*
X591775Y407117D01*
X591362Y407040D01*
X591103Y406810D01*
X590948Y406542D01*
Y405583D01*
G01Y406542D02*
X589450Y407117D01*
G01Y409450D02*
X592550D01*
X591930Y408990D01*
G01X589450D02*
Y409910D01*
G01Y412550D02*
X592550D01*
X591930Y412090D01*
G01X589450D02*
Y413010D01*
G01Y415650D02*
X589502Y415918D01*
X589657Y416225D01*
X589915Y416417D01*
X590277Y416493D01*
X590638Y416417D01*
X590948Y416187D01*
X591103Y415842D01*
Y415458D01*
X591207Y415228D01*
X591465Y415037D01*
X591827Y414960D01*
X592188Y415075D01*
X592447Y415343D01*
X592550Y415650D01*
X592447Y415957D01*
X592188Y416225D01*
X591827Y416340D01*
X591465Y416263D01*
X591207Y416072D01*
X591103Y415842D01*
Y415458D01*
X590948Y415113D01*
X590638Y414883D01*
X590277Y414807D01*
X589915Y414883D01*
X589657Y415075D01*
X589502Y415382D01*
X589450Y415650D01*
G01X601150Y418583D02*
X604250D01*
Y419542D01*
X604095Y419848D01*
X603888Y420040D01*
X603475Y420117D01*
X603062Y420040D01*
X602803Y419810D01*
X602648Y419542D01*
Y418583D01*
G01Y419542D02*
X601150Y420117D01*
G01X603733Y421722D02*
X604043Y421952D01*
X604198Y422220D01*
X604250Y422527D01*
X604147Y422910D01*
X603888Y423178D01*
X603578Y423255D01*
X603268Y423217D01*
X603010Y423063D01*
X602493Y422297D01*
X602132Y421952D01*
X601615Y421722D01*
X601150Y421645D01*
Y423255D01*
G01Y425473D02*
X601822Y425550D01*
X602390Y425665D01*
X602907Y425818D01*
X603475Y426010D01*
X604250Y426317D01*
Y424783D01*
G01X601512Y427998D02*
X601253Y428267D01*
X601150Y428573D01*
X601253Y428880D01*
X601563Y429148D01*
X602028Y429340D01*
X602493Y429417D01*
X603062D01*
X603527Y429340D01*
X603940Y429148D01*
X604147Y428918D01*
X604250Y428650D01*
X604147Y428343D01*
X603940Y428113D01*
X603630Y427960D01*
X603217Y427883D01*
X602855Y427960D01*
X602493Y428152D01*
X602287Y428382D01*
X602235Y428650D01*
X602338Y428957D01*
X602597Y429187D01*
X603062Y429417D01*
G01X615950Y136583D02*
X619050D01*
Y137542D01*
X618895Y137848D01*
X618688Y138040D01*
X618275Y138117D01*
X617862Y138040D01*
X617603Y137810D01*
X617448Y137542D01*
Y136583D01*
G01Y137542D02*
X615950Y138117D01*
G01X616570Y139607D02*
X616208Y139837D01*
X616002Y140143D01*
X615950Y140488D01*
X616002Y140795D01*
X616260Y141102D01*
X616570Y141293D01*
X616880Y141332D01*
X617242Y141255D01*
X617500Y140987D01*
X617603Y140718D01*
Y140373D01*
G01Y140718D02*
X617758Y140948D01*
X618017Y141140D01*
X618327Y141217D01*
X618637Y141140D01*
X618895Y140948D01*
X619050Y140603D01*
X618998Y140258D01*
X618792Y139913D01*
G01X618533Y142822D02*
X618843Y143052D01*
X618998Y143320D01*
X619050Y143627D01*
X618947Y144010D01*
X618688Y144278D01*
X618378Y144355D01*
X618068Y144317D01*
X617810Y144163D01*
X617293Y143397D01*
X616932Y143052D01*
X616415Y142822D01*
X615950Y142745D01*
Y144355D01*
G01X616312Y145998D02*
X616053Y146267D01*
X615950Y146573D01*
X616053Y146880D01*
X616363Y147148D01*
X616828Y147340D01*
X617293Y147417D01*
X617862D01*
X618327Y147340D01*
X618740Y147148D01*
X618947Y146918D01*
X619050Y146650D01*
X618947Y146343D01*
X618740Y146113D01*
X618430Y145960D01*
X618017Y145883D01*
X617655Y145960D01*
X617293Y146152D01*
X617087Y146382D01*
X617035Y146650D01*
X617138Y146957D01*
X617397Y147187D01*
X617862Y147417D01*
G01X615950Y148083D02*
X619050D01*
Y149042D01*
X618895Y149348D01*
X618688Y149540D01*
X618275Y149617D01*
X617862Y149540D01*
X617603Y149310D01*
X617448Y149042D01*
Y148083D01*
G01Y149042D02*
X615950Y149617D01*
G01Y152410D02*
X619050D01*
X616828Y150992D01*
Y152908D01*
G01X618533Y154322D02*
X618843Y154552D01*
X618998Y154820D01*
X619050Y155127D01*
X618947Y155510D01*
X618688Y155778D01*
X618378Y155855D01*
X618068Y155817D01*
X617810Y155663D01*
X617293Y154897D01*
X616932Y154552D01*
X616415Y154322D01*
X615950Y154245D01*
Y155855D01*
G01Y158150D02*
X616002Y158418D01*
X616157Y158725D01*
X616415Y158917D01*
X616777Y158993D01*
X617138Y158917D01*
X617448Y158687D01*
X617603Y158342D01*
Y157958D01*
X617707Y157728D01*
X617965Y157537D01*
X618327Y157460D01*
X618688Y157575D01*
X618947Y157843D01*
X619050Y158150D01*
X618947Y158457D01*
X618688Y158725D01*
X618327Y158840D01*
X617965Y158763D01*
X617707Y158572D01*
X617603Y158342D01*
Y157958D01*
X617448Y157613D01*
X617138Y157383D01*
X616777Y157307D01*
X616415Y157383D01*
X616157Y157575D01*
X616002Y157882D01*
X615950Y158150D01*
G01X615450Y160583D02*
X618550D01*
Y161542D01*
X618395Y161848D01*
X618188Y162040D01*
X617775Y162117D01*
X617362Y162040D01*
X617103Y161810D01*
X616948Y161542D01*
Y160583D01*
G01Y161542D02*
X615450Y162117D01*
G01Y164910D02*
X618550D01*
X616328Y163492D01*
Y165408D01*
G01X618033Y166822D02*
X618343Y167052D01*
X618498Y167320D01*
X618550Y167627D01*
X618447Y168010D01*
X618188Y168278D01*
X617878Y168355D01*
X617568Y168317D01*
X617310Y168163D01*
X616793Y167397D01*
X616432Y167052D01*
X615915Y166822D01*
X615450Y166745D01*
Y168355D01*
G01X615812Y169998D02*
X615553Y170267D01*
X615450Y170573D01*
X615553Y170880D01*
X615863Y171148D01*
X616328Y171340D01*
X616793Y171417D01*
X617362D01*
X617827Y171340D01*
X618240Y171148D01*
X618447Y170918D01*
X618550Y170650D01*
X618447Y170343D01*
X618240Y170113D01*
X617930Y169960D01*
X617517Y169883D01*
X617155Y169960D01*
X616793Y170152D01*
X616587Y170382D01*
X616535Y170650D01*
X616638Y170957D01*
X616897Y171187D01*
X617362Y171417D01*
G01X614450Y173083D02*
X617550D01*
Y174042D01*
X617395Y174348D01*
X617188Y174540D01*
X616775Y174617D01*
X616362Y174540D01*
X616103Y174310D01*
X615948Y174042D01*
Y173083D01*
G01Y174042D02*
X614450Y174617D01*
G01Y177410D02*
X617550D01*
X615328Y175992D01*
Y177908D01*
G01X615070Y179207D02*
X614708Y179437D01*
X614502Y179743D01*
X614450Y180088D01*
X614502Y180395D01*
X614760Y180702D01*
X615070Y180893D01*
X615380Y180932D01*
X615742Y180855D01*
X616000Y180587D01*
X616103Y180318D01*
Y179973D01*
G01Y180318D02*
X616258Y180548D01*
X616517Y180740D01*
X616827Y180817D01*
X617137Y180740D01*
X617395Y180548D01*
X617550Y180203D01*
X617498Y179858D01*
X617292Y179513D01*
G01X617550Y183150D02*
X617447Y182843D01*
X617188Y182613D01*
X616878Y182460D01*
X616465Y182345D01*
X616000Y182307D01*
X615535Y182345D01*
X615122Y182460D01*
X614812Y182613D01*
X614553Y182843D01*
X614450Y183150D01*
X614553Y183457D01*
X614812Y183687D01*
X615122Y183840D01*
X615535Y183955D01*
X616000Y183993D01*
X616465Y183955D01*
X616878Y183840D01*
X617188Y183687D01*
X617447Y183457D01*
X617550Y183150D01*
G01X605352Y189098D02*
X608452D01*
Y190057D01*
X608297Y190363D01*
X608090Y190555D01*
X607677Y190632D01*
X607264Y190555D01*
X607005Y190325D01*
X606850Y190057D01*
Y189098D01*
G01Y190057D02*
X605352Y190632D01*
G01X606644Y192237D02*
X607005Y192505D01*
X607212Y192735D01*
X607315Y193042D01*
X607212Y193310D01*
X607005Y193502D01*
X606695Y193655D01*
X606334Y193693D01*
X606024Y193655D01*
X605714Y193502D01*
X605455Y193272D01*
X605352Y193003D01*
X605455Y192697D01*
X605765Y192428D01*
X606230Y192275D01*
X606747Y192237D01*
X607419Y192313D01*
X607780Y192428D01*
X608142Y192620D01*
X608400Y192888D01*
X608452Y193157D01*
X608349Y193425D01*
X608090Y193617D01*
G01X605817Y195222D02*
X605559Y195452D01*
X605404Y195720D01*
X605352Y196065D01*
X605455Y196410D01*
X605662Y196678D01*
X606024Y196870D01*
X606437Y196908D01*
X606850Y196832D01*
X607109Y196640D01*
X607315Y196372D01*
X607367Y196103D01*
X607315Y195835D01*
X607109Y195490D01*
X608452Y195605D01*
Y196640D01*
G01X619450Y193457D02*
X622550D01*
Y194416D01*
X622395Y194722D01*
X622188Y194914D01*
X621775Y194991D01*
X621362Y194914D01*
X621103Y194684D01*
X620948Y194416D01*
Y193457D01*
G01Y194416D02*
X619450Y194991D01*
G01Y197324D02*
X622550D01*
X621930Y196864D01*
G01X619450D02*
Y197784D01*
G01X622550Y200424D02*
X622447Y200117D01*
X622188Y199887D01*
X621878Y199734D01*
X621465Y199619D01*
X621000Y199581D01*
X620535Y199619D01*
X620122Y199734D01*
X619812Y199887D01*
X619553Y200117D01*
X619450Y200424D01*
X619553Y200731D01*
X619812Y200961D01*
X620122Y201114D01*
X620535Y201229D01*
X621000Y201267D01*
X621465Y201229D01*
X621878Y201114D01*
X622188Y200961D01*
X622447Y200731D01*
X622550Y200424D01*
G01X620070Y202681D02*
X619708Y202911D01*
X619502Y203217D01*
X619450Y203562D01*
X619502Y203869D01*
X619760Y204176D01*
X620070Y204367D01*
X620380Y204406D01*
X620742Y204329D01*
X621000Y204061D01*
X621103Y203792D01*
Y203447D01*
G01Y203792D02*
X621258Y204022D01*
X621517Y204214D01*
X621827Y204291D01*
X622137Y204214D01*
X622395Y204022D01*
X622550Y203677D01*
X622498Y203332D01*
X622292Y202987D01*
G01X612950Y406083D02*
X616050D01*
Y407042D01*
X615895Y407348D01*
X615688Y407540D01*
X615275Y407617D01*
X614862Y407540D01*
X614603Y407310D01*
X614448Y407042D01*
Y406083D01*
G01Y407042D02*
X612950Y407617D01*
G01Y409950D02*
X616050D01*
X615430Y409490D01*
G01X612950D02*
Y410410D01*
G01X614242Y412322D02*
X614603Y412590D01*
X614810Y412820D01*
X614913Y413127D01*
X614810Y413395D01*
X614603Y413587D01*
X614293Y413740D01*
X613932Y413778D01*
X613622Y413740D01*
X613312Y413587D01*
X613053Y413357D01*
X612950Y413088D01*
X613053Y412782D01*
X613363Y412513D01*
X613828Y412360D01*
X614345Y412322D01*
X615017Y412398D01*
X615378Y412513D01*
X615740Y412705D01*
X615998Y412973D01*
X616050Y413242D01*
X615947Y413510D01*
X615688Y413702D01*
G01X613312Y415498D02*
X613053Y415767D01*
X612950Y416073D01*
X613053Y416380D01*
X613363Y416648D01*
X613828Y416840D01*
X614293Y416917D01*
X614862D01*
X615327Y416840D01*
X615740Y416648D01*
X615947Y416418D01*
X616050Y416150D01*
X615947Y415843D01*
X615740Y415613D01*
X615430Y415460D01*
X615017Y415383D01*
X614655Y415460D01*
X614293Y415652D01*
X614087Y415882D01*
X614035Y416150D01*
X614138Y416457D01*
X614397Y416687D01*
X614862Y416917D01*
G01X612450Y418583D02*
X615550D01*
Y419542D01*
X615395Y419848D01*
X615188Y420040D01*
X614775Y420117D01*
X614362Y420040D01*
X614103Y419810D01*
X613948Y419542D01*
Y418583D01*
G01Y419542D02*
X612450Y420117D01*
G01X615033Y421722D02*
X615343Y421952D01*
X615498Y422220D01*
X615550Y422527D01*
X615447Y422910D01*
X615188Y423178D01*
X614878Y423255D01*
X614568Y423217D01*
X614310Y423063D01*
X613793Y422297D01*
X613432Y421952D01*
X612915Y421722D01*
X612450Y421645D01*
Y423255D01*
G01Y425550D02*
X612502Y425818D01*
X612657Y426125D01*
X612915Y426317D01*
X613277Y426393D01*
X613638Y426317D01*
X613948Y426087D01*
X614103Y425742D01*
Y425358D01*
X614207Y425128D01*
X614465Y424937D01*
X614827Y424860D01*
X615188Y424975D01*
X615447Y425243D01*
X615550Y425550D01*
X615447Y425857D01*
X615188Y426125D01*
X614827Y426240D01*
X614465Y426163D01*
X614207Y425972D01*
X614103Y425742D01*
Y425358D01*
X613948Y425013D01*
X613638Y424783D01*
X613277Y424707D01*
X612915Y424783D01*
X612657Y424975D01*
X612502Y425282D01*
X612450Y425550D01*
G01X615550Y428650D02*
X615447Y428343D01*
X615188Y428113D01*
X614878Y427960D01*
X614465Y427845D01*
X614000Y427807D01*
X613535Y427845D01*
X613122Y427960D01*
X612812Y428113D01*
X612553Y428343D01*
X612450Y428650D01*
X612553Y428957D01*
X612812Y429187D01*
X613122Y429340D01*
X613535Y429455D01*
X614000Y429493D01*
X614465Y429455D01*
X614878Y429340D01*
X615188Y429187D01*
X615447Y428957D01*
X615550Y428650D01*
G01X645417Y94950D02*
Y98050D01*
X644458D01*
X644152Y97895D01*
X643960Y97688D01*
X643883Y97275D01*
X643960Y96862D01*
X644190Y96603D01*
X644458Y96448D01*
X645417D01*
G01X644458D02*
X643883Y94950D01*
G01X641090D02*
Y98050D01*
X642508Y95828D01*
X640592D01*
G01X638450Y94950D02*
Y98050D01*
X638910Y97430D01*
G01Y94950D02*
X637990D01*
G01X635350D02*
Y98050D01*
X635810Y97430D01*
G01Y94950D02*
X634890D01*
G01X645417Y101482D02*
Y104582D01*
X644458D01*
X644152Y104427D01*
X643960Y104220D01*
X643883Y103807D01*
X643960Y103394D01*
X644190Y103135D01*
X644458Y102980D01*
X645417D01*
G01X644458D02*
X643883Y101482D01*
G01X641090D02*
Y104582D01*
X642508Y102360D01*
X640592D01*
G01X638450Y101482D02*
Y104582D01*
X638910Y103962D01*
G01Y101482D02*
X637990D01*
G01X636193Y101947D02*
X635963Y101689D01*
X635695Y101534D01*
X635350Y101482D01*
X635005Y101585D01*
X634737Y101792D01*
X634545Y102154D01*
X634507Y102567D01*
X634583Y102980D01*
X634775Y103239D01*
X635043Y103445D01*
X635312Y103497D01*
X635580Y103445D01*
X635925Y103239D01*
X635810Y104582D01*
X634775D01*
G01X645417Y107482D02*
Y110582D01*
X644458D01*
X644152Y110427D01*
X643960Y110220D01*
X643883Y109807D01*
X643960Y109394D01*
X644190Y109135D01*
X644458Y108980D01*
X645417D01*
G01X644458D02*
X643883Y107482D01*
G01X641090D02*
Y110582D01*
X642508Y108360D01*
X640592D01*
G01X638450Y107482D02*
Y110582D01*
X638910Y109962D01*
G01Y107482D02*
X637990D01*
G01X635427D02*
X635350Y108154D01*
X635235Y108722D01*
X635082Y109239D01*
X634890Y109807D01*
X634583Y110582D01*
X636117D01*
G01X623950Y193457D02*
X627050D01*
Y194416D01*
X626895Y194722D01*
X626688Y194914D01*
X626275Y194991D01*
X625862Y194914D01*
X625603Y194684D01*
X625448Y194416D01*
Y193457D01*
G01Y194416D02*
X623950Y194991D01*
G01Y197324D02*
X627050D01*
X626430Y196864D01*
G01X623950D02*
Y197784D01*
G01X627050Y200424D02*
X626947Y200117D01*
X626688Y199887D01*
X626378Y199734D01*
X625965Y199619D01*
X625500Y199581D01*
X625035Y199619D01*
X624622Y199734D01*
X624312Y199887D01*
X624053Y200117D01*
X623950Y200424D01*
X624053Y200731D01*
X624312Y200961D01*
X624622Y201114D01*
X625035Y201229D01*
X625500Y201267D01*
X625965Y201229D01*
X626378Y201114D01*
X626688Y200961D01*
X626947Y200731D01*
X627050Y200424D01*
G01X626533Y202796D02*
X626843Y203026D01*
X626998Y203294D01*
X627050Y203601D01*
X626947Y203984D01*
X626688Y204252D01*
X626378Y204329D01*
X626068Y204291D01*
X625810Y204137D01*
X625293Y203371D01*
X624932Y203026D01*
X624415Y202796D01*
X623950Y202719D01*
Y204329D01*
G01X628450Y193457D02*
X631550D01*
Y194416D01*
X631395Y194722D01*
X631188Y194914D01*
X630775Y194991D01*
X630362Y194914D01*
X630103Y194684D01*
X629948Y194416D01*
Y193457D01*
G01Y194416D02*
X628450Y194991D01*
G01Y197324D02*
X631550D01*
X630930Y196864D01*
G01X628450D02*
Y197784D01*
G01X631550Y200424D02*
X631447Y200117D01*
X631188Y199887D01*
X630878Y199734D01*
X630465Y199619D01*
X630000Y199581D01*
X629535Y199619D01*
X629122Y199734D01*
X628812Y199887D01*
X628553Y200117D01*
X628450Y200424D01*
X628553Y200731D01*
X628812Y200961D01*
X629122Y201114D01*
X629535Y201229D01*
X630000Y201267D01*
X630465Y201229D01*
X630878Y201114D01*
X631188Y200961D01*
X631447Y200731D01*
X631550Y200424D01*
G01X628450Y203524D02*
X631550D01*
X630930Y203064D01*
G01X628450D02*
Y203984D01*
G54D13*
G01X227000Y236500D02*
X117000D01*
Y211500D01*
X227000D01*
Y236500D01*
G54D14*
G01X214965Y220753D02*
X214045Y219970D01*
X213010Y219500D01*
X212090D01*
X211170Y219970D01*
X210480Y220753D01*
X210135Y221850D01*
X210365Y222947D01*
X210940Y223887D01*
X211975Y224513D01*
X213355Y224827D01*
X214160Y225453D01*
X214505Y226550D01*
X214275Y227647D01*
X213700Y228430D01*
X212895Y228900D01*
X212090D01*
X211285Y228587D01*
X210595Y227803D01*
G01X201050Y219500D02*
X205650D01*
Y228900D01*
X201050D01*
G01X202890Y224357D02*
X205650D01*
G01X196450Y219500D02*
Y228900D01*
X193575D01*
X192655Y228430D01*
X192080Y227803D01*
X191850Y226550D01*
X192080Y225297D01*
X192770Y224513D01*
X193575Y224043D01*
X196450D01*
G01X193575D02*
X191850Y219500D01*
G01X186330Y228900D02*
X183570D01*
G01X184950D02*
Y219500D01*
G01X186330D02*
X183570D01*
G01X178625D02*
X175750Y228900D01*
X172875Y219500D01*
G01X173910Y222790D02*
X177590D01*
G01X168850Y228900D02*
Y219500D01*
X164250D01*
G01X150795D02*
Y228900D01*
X145505Y219500D01*
Y228900D01*
G01X138950Y219500D02*
X139870Y219657D01*
X140675Y220283D01*
X141365Y221223D01*
X141825Y222320D01*
X142055Y223573D01*
Y224827D01*
X141825Y226080D01*
X141365Y227177D01*
X140675Y228117D01*
X139870Y228743D01*
X138950Y228900D01*
X138030Y228743D01*
X137225Y228117D01*
X136535Y227177D01*
X136075Y226080D01*
X135845Y224827D01*
Y223573D01*
X136075Y222320D01*
X136535Y221223D01*
X137225Y220283D01*
X138030Y219657D01*
X138950Y219500D01*
G01X129750Y219187D02*
X129980Y219343D01*
Y219657D01*
X129750Y219813D01*
X129520Y219657D01*
Y219343D01*
X129750Y219187D01*
M02*
